(kicad_sch
	(version 20250114)
	(generator "eeschema")
	(generator_version "9.0")
	(paper "A3")
	(title_block
		(title "Antmicro Baseboard for Jetson AGX Thor")
		(date "2026-02-17")
		(rev "1.1.0")
		(company "Antmicro Ltd")
		(comment 1 "www.antmicro.com")
	)
	(text "SFP28"
		(exclude_from_sim no)
		(at 189.23 85.598 0)
		(effects
			(font
				(size 2.54 2.54)
				(thickness 0.4)
				(bold yes)
			)
			(justify left bottom)
		)
	)
	(junction
		(at 293.37 147.32)
		(diameter 0)
		(color 0 0 0 0)
	)
	(junction
		(at 240.03 147.32)
		(diameter 0)
		(color 0 0 0 0)
	)
	(junction
		(at 182.88 113.03)
		(diameter 0)
		(color 0 0 0 0)
	)
	(junction
		(at 275.59 147.32)
		(diameter 0)
		(color 0 0 0 0)
	)
	(junction
		(at 173.99 92.71)
		(diameter 0)
		(color 0 0 0 0)
	)
	(junction
		(at 158.75 138.43)
		(diameter 0)
		(color 0 0 0 0)
	)
	(junction
		(at 257.81 147.32)
		(diameter 0)
		(color 0 0 0 0)
	)
	(junction
		(at 212.09 161.29)
		(diameter 0)
		(color 0 0 0 0)
	)
	(junction
		(at 241.3 127)
		(diameter 0)
		(color 0 0 0 0)
	)
	(junction
		(at 302.26 147.32)
		(diameter 0)
		(color 0 0 0 0)
	)
	(junction
		(at 166.37 113.03)
		(diameter 0)
		(color 0 0 0 0)
	)
	(junction
		(at 236.22 147.32)
		(diameter 0)
		(color 0 0 0 0)
	)
	(junction
		(at 156.21 92.71)
		(diameter 0)
		(color 0 0 0 0)
	)
	(junction
		(at 166.37 135.89)
		(diameter 0)
		(color 0 0 0 0)
	)
	(junction
		(at 240.03 161.29)
		(diameter 0)
		(color 0 0 0 0)
	)
	(junction
		(at 248.92 147.32)
		(diameter 0)
		(color 0 0 0 0)
	)
	(junction
		(at 266.7 147.32)
		(diameter 0)
		(color 0 0 0 0)
	)
	(junction
		(at 168.91 140.97)
		(diameter 0)
		(color 0 0 0 0)
	)
	(junction
		(at 182.88 118.11)
		(diameter 0)
		(color 0 0 0 0)
	)
	(junction
		(at 165.1 92.71)
		(diameter 0)
		(color 0 0 0 0)
	)
	(junction
		(at 284.48 147.32)
		(diameter 0)
		(color 0 0 0 0)
	)
	(junction
		(at 158.75 113.03)
		(diameter 0)
		(color 0 0 0 0)
	)
	(junction
		(at 147.32 133.35)
		(diameter 0)
		(color 0 0 0 0)
	)
	(bus_entry
		(at 133.35 157.48)
		(size 1.27 1.27)
		(stroke
			(width 0)
			(type default)
		)
	)
	(bus_entry
		(at 120.65 127)
		(size 1.27 1.27)
		(stroke
			(width 0)
			(type default)
		)
	)
	(bus_entry
		(at 120.65 124.46)
		(size 1.27 1.27)
		(stroke
			(width 0)
			(type default)
		)
	)
	(bus_entry
		(at 133.35 160.02)
		(size 1.27 1.27)
		(stroke
			(width 0)
			(type default)
		)
	)
	(bus_entry
		(at 133.35 149.86)
		(size 1.27 1.27)
		(stroke
			(width 0)
			(type default)
		)
	)
	(bus_entry
		(at 133.35 152.4)
		(size 1.27 1.27)
		(stroke
			(width 0)
			(type default)
		)
	)
	(wire
		(pts
			(xy 240.03 161.29) (xy 240.03 157.48)
		)
		(stroke
			(width 0)
			(type default)
		)
	)
	(wire
		(pts
			(xy 134.62 151.13) (xy 151.13 151.13)
		)
		(stroke
			(width 0)
			(type default)
		)
	)
	(wire
		(pts
			(xy 236.22 152.4) (xy 236.22 147.32)
		)
		(stroke
			(width 0)
			(type default)
		)
	)
	(wire
		(pts
			(xy 240.03 147.32) (xy 248.92 147.32)
		)
		(stroke
			(width 0)
			(type default)
		)
	)
	(bus
		(pts
			(xy 120.65 124.46) (xy 119.38 123.19)
		)
		(stroke
			(width 0)
			(type default)
		)
	)
	(wire
		(pts
			(xy 266.7 147.32) (xy 275.59 147.32)
		)
		(stroke
			(width 0)
			(type default)
		)
	)
	(bus
		(pts
			(xy 133.35 152.4) (xy 133.35 157.48)
		)
		(stroke
			(width 0)
			(type default)
		)
	)
	(bus
		(pts
			(xy 133.35 149.86) (xy 132.08 148.59)
		)
		(stroke
			(width 0)
			(type default)
		)
	)
	(wire
		(pts
			(xy 156.21 100.33) (xy 156.21 99.06)
		)
		(stroke
			(width 0)
			(type default)
		)
	)
	(wire
		(pts
			(xy 168.91 143.51) (xy 175.26 143.51)
		)
		(stroke
			(width 0)
			(type default)
		)
	)
	(wire
		(pts
			(xy 284.48 147.32) (xy 284.48 152.4)
		)
		(stroke
			(width 0)
			(type default)
		)
	)
	(wire
		(pts
			(xy 236.22 161.29) (xy 236.22 157.48)
		)
		(stroke
			(width 0)
			(type default)
		)
	)
	(wire
		(pts
			(xy 143.51 128.27) (xy 185.42 128.27)
		)
		(stroke
			(width 0)
			(type default)
		)
	)
	(wire
		(pts
			(xy 147.32 133.35) (xy 147.32 120.65)
		)
		(stroke
			(width 0)
			(type default)
		)
	)
	(wire
		(pts
			(xy 257.81 147.32) (xy 266.7 147.32)
		)
		(stroke
			(width 0)
			(type default)
		)
	)
	(wire
		(pts
			(xy 166.37 115.57) (xy 166.37 113.03)
		)
		(stroke
			(width 0)
			(type default)
		)
	)
	(wire
		(pts
			(xy 311.15 157.48) (xy 311.15 162.56)
		)
		(stroke
			(width 0)
			(type default)
		)
	)
	(wire
		(pts
			(xy 307.34 130.81) (xy 307.34 128.27)
		)
		(stroke
			(width 0)
			(type default)
		)
	)
	(wire
		(pts
			(xy 165.1 142.24) (xy 165.1 140.97)
		)
		(stroke
			(width 0)
			(type default)
		)
	)
	(wire
		(pts
			(xy 157.48 138.43) (xy 158.75 138.43)
		)
		(stroke
			(width 0)
			(type default)
		)
	)
	(wire
		(pts
			(xy 302.26 147.32) (xy 302.26 152.4)
		)
		(stroke
			(width 0)
			(type default)
		)
	)
	(wire
		(pts
			(xy 302.26 157.48) (xy 302.26 162.56)
		)
		(stroke
			(width 0)
			(type default)
		)
	)
	(wire
		(pts
			(xy 304.8 130.81) (xy 307.34 130.81)
		)
		(stroke
			(width 0)
			(type default)
		)
	)
	(wire
		(pts
			(xy 173.99 100.33) (xy 173.99 99.06)
		)
		(stroke
			(width 0)
			(type default)
		)
	)
	(wire
		(pts
			(xy 151.13 113.03) (xy 158.75 113.03)
		)
		(stroke
			(width 0)
			(type default)
		)
	)
	(wire
		(pts
			(xy 226.06 147.32) (xy 236.22 147.32)
		)
		(stroke
			(width 0)
			(type default)
		)
	)
	(wire
		(pts
			(xy 158.75 138.43) (xy 185.42 138.43)
		)
		(stroke
			(width 0)
			(type default)
		)
	)
	(wire
		(pts
			(xy 307.34 119.38) (xy 307.34 123.19)
		)
		(stroke
			(width 0)
			(type default)
		)
	)
	(wire
		(pts
			(xy 275.59 147.32) (xy 284.48 147.32)
		)
		(stroke
			(width 0)
			(type default)
		)
	)
	(wire
		(pts
			(xy 210.82 158.75) (xy 212.09 158.75)
		)
		(stroke
			(width 0)
			(type default)
		)
	)
	(wire
		(pts
			(xy 156.21 158.75) (xy 185.42 158.75)
		)
		(stroke
			(width 0)
			(type default)
		)
	)
	(wire
		(pts
			(xy 240.03 152.4) (xy 240.03 147.32)
		)
		(stroke
			(width 0)
			(type default)
		)
	)
	(wire
		(pts
			(xy 121.92 125.73) (xy 138.43 125.73)
		)
		(stroke
			(width 0)
			(type default)
		)
	)
	(wire
		(pts
			(xy 160.02 161.29) (xy 185.42 161.29)
		)
		(stroke
			(width 0)
			(type default)
		)
	)
	(wire
		(pts
			(xy 121.92 128.27) (xy 138.43 128.27)
		)
		(stroke
			(width 0)
			(type default)
		)
	)
	(wire
		(pts
			(xy 165.1 140.97) (xy 168.91 140.97)
		)
		(stroke
			(width 0)
			(type default)
		)
	)
	(wire
		(pts
			(xy 212.09 161.29) (xy 212.09 162.56)
		)
		(stroke
			(width 0)
			(type default)
		)
	)
	(wire
		(pts
			(xy 241.3 127) (xy 241.3 124.46)
		)
		(stroke
			(width 0)
			(type default)
		)
	)
	(wire
		(pts
			(xy 156.21 151.13) (xy 185.42 151.13)
		)
		(stroke
			(width 0)
			(type default)
		)
	)
	(wire
		(pts
			(xy 293.37 147.32) (xy 302.26 147.32)
		)
		(stroke
			(width 0)
			(type default)
		)
	)
	(wire
		(pts
			(xy 185.42 120.65) (xy 182.88 120.65)
		)
		(stroke
			(width 0)
			(type default)
		)
	)
	(wire
		(pts
			(xy 257.81 147.32) (xy 257.81 152.4)
		)
		(stroke
			(width 0)
			(type default)
		)
	)
	(wire
		(pts
			(xy 173.99 92.71) (xy 182.88 92.71)
		)
		(stroke
			(width 0)
			(type default)
		)
	)
	(wire
		(pts
			(xy 182.88 118.11) (xy 185.42 118.11)
		)
		(stroke
			(width 0)
			(type default)
		)
	)
	(wire
		(pts
			(xy 151.13 146.05) (xy 151.13 120.65)
		)
		(stroke
			(width 0)
			(type default)
		)
	)
	(wire
		(pts
			(xy 165.1 100.33) (xy 165.1 99.06)
		)
		(stroke
			(width 0)
			(type default)
		)
	)
	(wire
		(pts
			(xy 275.59 157.48) (xy 275.59 162.56)
		)
		(stroke
			(width 0)
			(type default)
		)
	)
	(wire
		(pts
			(xy 147.32 133.35) (xy 185.42 133.35)
		)
		(stroke
			(width 0)
			(type default)
		)
	)
	(bus
		(pts
			(xy 133.35 152.4) (xy 133.35 149.86)
		)
		(stroke
			(width 0)
			(type default)
		)
	)
	(wire
		(pts
			(xy 285.75 113.03) (xy 285.75 114.3)
		)
		(stroke
			(width 0)
			(type default)
		)
	)
	(wire
		(pts
			(xy 143.51 125.73) (xy 185.42 125.73)
		)
		(stroke
			(width 0)
			(type default)
		)
	)
	(wire
		(pts
			(xy 248.92 147.32) (xy 248.92 152.4)
		)
		(stroke
			(width 0)
			(type default)
		)
	)
	(wire
		(pts
			(xy 212.09 158.75) (xy 212.09 161.29)
		)
		(stroke
			(width 0)
			(type default)
		)
	)
	(wire
		(pts
			(xy 151.13 113.03) (xy 151.13 115.57)
		)
		(stroke
			(width 0)
			(type default)
		)
	)
	(wire
		(pts
			(xy 236.22 147.32) (xy 240.03 147.32)
		)
		(stroke
			(width 0)
			(type default)
		)
	)
	(wire
		(pts
			(xy 156.21 92.71) (xy 156.21 93.98)
		)
		(stroke
			(width 0)
			(type default)
		)
	)
	(wire
		(pts
			(xy 285.75 119.38) (xy 285.75 123.19)
		)
		(stroke
			(width 0)
			(type default)
		)
	)
	(wire
		(pts
			(xy 151.13 146.05) (xy 185.42 146.05)
		)
		(stroke
			(width 0)
			(type default)
		)
	)
	(wire
		(pts
			(xy 236.22 161.29) (xy 240.03 161.29)
		)
		(stroke
			(width 0)
			(type default)
		)
	)
	(bus
		(pts
			(xy 129.54 148.59) (xy 132.08 148.59)
		)
		(stroke
			(width 0)
			(type default)
		)
	)
	(wire
		(pts
			(xy 182.88 113.03) (xy 182.88 118.11)
		)
		(stroke
			(width 0)
			(type default)
		)
	)
	(bus
		(pts
			(xy 120.65 124.46) (xy 120.65 127)
		)
		(stroke
			(width 0)
			(type default)
		)
	)
	(wire
		(pts
			(xy 180.34 140.97) (xy 185.42 140.97)
		)
		(stroke
			(width 0)
			(type default)
		)
	)
	(wire
		(pts
			(xy 182.88 120.65) (xy 182.88 118.11)
		)
		(stroke
			(width 0)
			(type default)
		)
	)
	(wire
		(pts
			(xy 168.91 140.97) (xy 175.26 140.97)
		)
		(stroke
			(width 0)
			(type default)
		)
	)
	(wire
		(pts
			(xy 241.3 127) (xy 241.3 128.27)
		)
		(stroke
			(width 0)
			(type default)
		)
	)
	(wire
		(pts
			(xy 293.37 157.48) (xy 293.37 162.56)
		)
		(stroke
			(width 0)
			(type default)
		)
	)
	(wire
		(pts
			(xy 248.92 147.32) (xy 257.81 147.32)
		)
		(stroke
			(width 0)
			(type default)
		)
	)
	(wire
		(pts
			(xy 165.1 135.89) (xy 166.37 135.89)
		)
		(stroke
			(width 0)
			(type default)
		)
	)
	(wire
		(pts
			(xy 129.54 133.35) (xy 138.43 133.35)
		)
		(stroke
			(width 0)
			(type default)
		)
	)
	(wire
		(pts
			(xy 293.37 147.32) (xy 293.37 152.4)
		)
		(stroke
			(width 0)
			(type default)
		)
	)
	(wire
		(pts
			(xy 158.75 115.57) (xy 158.75 113.03)
		)
		(stroke
			(width 0)
			(type default)
		)
	)
	(wire
		(pts
			(xy 228.6 119.38) (xy 242.57 119.38)
		)
		(stroke
			(width 0)
			(type default)
		)
	)
	(wire
		(pts
			(xy 248.92 157.48) (xy 248.92 162.56)
		)
		(stroke
			(width 0)
			(type default)
		)
	)
	(wire
		(pts
			(xy 228.6 121.92) (xy 242.57 121.92)
		)
		(stroke
			(width 0)
			(type default)
		)
	)
	(wire
		(pts
			(xy 266.7 157.48) (xy 266.7 162.56)
		)
		(stroke
			(width 0)
			(type default)
		)
	)
	(wire
		(pts
			(xy 158.75 120.65) (xy 158.75 138.43)
		)
		(stroke
			(width 0)
			(type default)
		)
	)
	(wire
		(pts
			(xy 180.34 143.51) (xy 185.42 143.51)
		)
		(stroke
			(width 0)
			(type default)
		)
	)
	(wire
		(pts
			(xy 266.7 147.32) (xy 266.7 152.4)
		)
		(stroke
			(width 0)
			(type default)
		)
	)
	(wire
		(pts
			(xy 166.37 113.03) (xy 182.88 113.03)
		)
		(stroke
			(width 0)
			(type default)
		)
	)
	(wire
		(pts
			(xy 134.62 153.67) (xy 154.94 153.67)
		)
		(stroke
			(width 0)
			(type default)
		)
	)
	(wire
		(pts
			(xy 166.37 120.65) (xy 166.37 135.89)
		)
		(stroke
			(width 0)
			(type default)
		)
	)
	(wire
		(pts
			(xy 147.32 113.03) (xy 147.32 115.57)
		)
		(stroke
			(width 0)
			(type default)
		)
	)
	(wire
		(pts
			(xy 242.57 124.46) (xy 241.3 124.46)
		)
		(stroke
			(width 0)
			(type default)
		)
	)
	(wire
		(pts
			(xy 240.03 161.29) (xy 240.03 162.56)
		)
		(stroke
			(width 0)
			(type default)
		)
	)
	(wire
		(pts
			(xy 158.75 113.03) (xy 166.37 113.03)
		)
		(stroke
			(width 0)
			(type default)
		)
	)
	(wire
		(pts
			(xy 168.91 140.97) (xy 168.91 143.51)
		)
		(stroke
			(width 0)
			(type default)
		)
	)
	(wire
		(pts
			(xy 307.34 113.03) (xy 307.34 114.3)
		)
		(stroke
			(width 0)
			(type default)
		)
	)
	(wire
		(pts
			(xy 302.26 147.32) (xy 311.15 147.32)
		)
		(stroke
			(width 0)
			(type default)
		)
	)
	(wire
		(pts
			(xy 228.6 116.84) (xy 242.57 116.84)
		)
		(stroke
			(width 0)
			(type default)
		)
	)
	(wire
		(pts
			(xy 134.62 161.29) (xy 154.94 161.29)
		)
		(stroke
			(width 0)
			(type default)
		)
	)
	(bus
		(pts
			(xy 133.35 157.48) (xy 133.35 160.02)
		)
		(stroke
			(width 0)
			(type default)
		)
	)
	(wire
		(pts
			(xy 311.15 147.32) (xy 311.15 152.4)
		)
		(stroke
			(width 0)
			(type default)
		)
	)
	(wire
		(pts
			(xy 283.21 130.81) (xy 285.75 130.81)
		)
		(stroke
			(width 0)
			(type default)
		)
	)
	(wire
		(pts
			(xy 173.99 93.98) (xy 173.99 92.71)
		)
		(stroke
			(width 0)
			(type default)
		)
	)
	(wire
		(pts
			(xy 134.62 158.75) (xy 151.13 158.75)
		)
		(stroke
			(width 0)
			(type default)
		)
	)
	(wire
		(pts
			(xy 143.51 133.35) (xy 147.32 133.35)
		)
		(stroke
			(width 0)
			(type default)
		)
	)
	(wire
		(pts
			(xy 160.02 153.67) (xy 185.42 153.67)
		)
		(stroke
			(width 0)
			(type default)
		)
	)
	(wire
		(pts
			(xy 156.21 91.44) (xy 156.21 92.71)
		)
		(stroke
			(width 0)
			(type default)
		)
	)
	(bus
		(pts
			(xy 116.84 123.19) (xy 119.38 123.19)
		)
		(stroke
			(width 0)
			(type default)
		)
	)
	(wire
		(pts
			(xy 166.37 135.89) (xy 185.42 135.89)
		)
		(stroke
			(width 0)
			(type default)
		)
	)
	(wire
		(pts
			(xy 241.3 127) (xy 242.57 127)
		)
		(stroke
			(width 0)
			(type default)
		)
	)
	(wire
		(pts
			(xy 257.81 157.48) (xy 257.81 162.56)
		)
		(stroke
			(width 0)
			(type default)
		)
	)
	(wire
		(pts
			(xy 165.1 92.71) (xy 165.1 93.98)
		)
		(stroke
			(width 0)
			(type default)
		)
	)
	(wire
		(pts
			(xy 210.82 161.29) (xy 212.09 161.29)
		)
		(stroke
			(width 0)
			(type default)
		)
	)
	(wire
		(pts
			(xy 284.48 147.32) (xy 293.37 147.32)
		)
		(stroke
			(width 0)
			(type default)
		)
	)
	(wire
		(pts
			(xy 284.48 157.48) (xy 284.48 162.56)
		)
		(stroke
			(width 0)
			(type default)
		)
	)
	(wire
		(pts
			(xy 182.88 92.71) (xy 182.88 113.03)
		)
		(stroke
			(width 0)
			(type default)
		)
	)
	(wire
		(pts
			(xy 156.21 92.71) (xy 165.1 92.71)
		)
		(stroke
			(width 0)
			(type default)
		)
	)
	(wire
		(pts
			(xy 285.75 128.27) (xy 285.75 130.81)
		)
		(stroke
			(width 0)
			(type default)
		)
	)
	(wire
		(pts
			(xy 275.59 147.32) (xy 275.59 152.4)
		)
		(stroke
			(width 0)
			(type default)
		)
	)
	(wire
		(pts
			(xy 173.99 92.71) (xy 165.1 92.71)
		)
		(stroke
			(width 0)
			(type default)
		)
	)
	(label "SFI.RX-"
		(at 144.78 161.29 180)
		(effects
			(font
				(size 1.27 1.27)
			)
			(justify right bottom)
		)
	)
	(label "SCL_SFP"
		(at 176.53 128.27 0)
		(effects
			(font
				(size 1.27 1.27)
			)
			(justify left bottom)
		)
	)
	(label "SCL_SFP"
		(at 228.6 119.38 0)
		(effects
			(font
				(size 1.27 1.27)
			)
			(justify left bottom)
		)
	)
	(label "SFI.TX-"
		(at 144.78 153.67 180)
		(effects
			(font
				(size 1.27 1.27)
			)
			(justify right bottom)
		)
	)
	(label "SFP_MOD_ABS"
		(at 228.6 121.92 0)
		(effects
			(font
				(size 1.27 1.27)
			)
			(justify left bottom)
		)
	)
	(label "SFI.TX+"
		(at 144.78 151.13 180)
		(effects
			(font
				(size 1.27 1.27)
			)
			(justify right bottom)
		)
	)
	(label "SDA_SFP"
		(at 176.53 125.73 0)
		(effects
			(font
				(size 1.27 1.27)
			)
			(justify left bottom)
		)
	)
	(label "SFI.RX+"
		(at 144.78 158.75 180)
		(effects
			(font
				(size 1.27 1.27)
			)
			(justify right bottom)
		)
	)
	(label "SDA_SFP"
		(at 228.6 116.84 0)
		(effects
			(font
				(size 1.27 1.27)
			)
			(justify left bottom)
		)
	)
	(label "SFI_CONN_TX_P"
		(at 165.1 151.13 0)
		(effects
			(font
				(size 1.27 1.27)
			)
			(justify left bottom)
		)
	)
	(label "SFI_CONN_RX_P"
		(at 165.1 158.75 0)
		(effects
			(font
				(size 1.27 1.27)
			)
			(justify left bottom)
		)
	)
	(label "SH"
		(at 236.22 147.32 180)
		(effects
			(font
				(size 1.27 1.27)
			)
			(justify right bottom)
		)
	)
	(label "I2C_{SFP}.SCL"
		(at 121.92 128.27 0)
		(effects
			(font
				(size 1.27 1.27)
			)
			(justify left bottom)
		)
	)
	(label "I2C_{SFP}.SDA"
		(at 121.92 125.73 0)
		(effects
			(font
				(size 1.27 1.27)
			)
			(justify left bottom)
		)
	)
	(label "SFI_CONN_TX_N"
		(at 165.1 153.67 0)
		(effects
			(font
				(size 1.27 1.27)
			)
			(justify left bottom)
		)
	)
	(label "SFP_MOD_ABS"
		(at 171.45 133.35 0)
		(effects
			(font
				(size 1.27 1.27)
			)
			(justify left bottom)
		)
	)
	(label "SFI_CONN_RX_N"
		(at 165.1 161.29 0)
		(effects
			(font
				(size 1.27 1.27)
			)
			(justify left bottom)
		)
	)
	(hierarchical_label "MOD_ABS"
		(shape output)
		(at 129.54 133.35 180)
		(effects
			(font
				(size 1.27 1.27)
			)
			(justify right)
		)
	)
	(hierarchical_label "SFP_LEDG"
		(shape input)
		(at 304.8 130.81 180)
		(effects
			(font
				(size 1.27 1.27)
			)
			(justify right)
		)
	)
	(hierarchical_label "I2C_{SFP}{I2C}"
		(shape bidirectional)
		(at 116.84 123.19 180)
		(effects
			(font
				(size 1.27 1.27)
			)
			(justify right)
		)
	)
	(hierarchical_label "SFP_LEDY"
		(shape input)
		(at 283.21 130.81 180)
		(effects
			(font
				(size 1.27 1.27)
			)
			(justify right)
		)
	)
	(hierarchical_label "SFI{SFI}"
		(shape bidirectional)
		(at 129.54 148.59 180)
		(effects
			(font
				(size 1.27 1.27)
			)
			(justify right)
		)
	)
	(rule_area
		(polyline
			(pts
				(xy 134.62 147.32) (xy 184.15 147.32) (xy 184.15 164.465) (xy 134.62 164.465)
			)
			(stroke
				(width 0)
				(type dash)
			)
			(fill
				(type none)
			)
		)
	)
	(netclass_flag ""
		(length 2.54)
		(shape round)
		(at 134.62 147.32 0)
		(effects
			(font
				(size 1.27 1.27)
			)
			(justify left bottom)
		)
		(property "Netclass" "85Ohm-diff_SFI"
			(at 133.604 144.78 0)
			(effects
				(font
					(size 1.27 1.27)
				)
				(justify right)
			)
		)
		(property "Component Class" ""
			(at -85.09 48.26 0)
			(effects
				(font
					(size 1.27 1.27)
					(italic yes)
				)
			)
		)
	)
	(symbol
		(lib_id "antmicroResistors0402:R_1k_0402")
		(at 158.75 120.65 90)
		(unit 1)
		(exclude_from_sim no)
		(in_bom yes)
		(on_board yes)
		(dnp no)
		(property "Reference" "R189"
			(at 160.02 116.84 90)
			(effects
				(font
					(size 1.27 1.27)
					(thickness 0.15)
				)
				(justify right)
			)
		)
		(property "Value" "R_1k_0402"
			(at 171.45 100.33 0)
			(effects
				(font
					(size 1.27 1.27)
					(thickness 0.15)
				)
				(justify left bottom)
				(hide yes)
			)
		)
		(property "Footprint" "antmicro-footprints:R_0402_1005Metric"
			(at 173.99 100.33 0)
			(effects
				(font
					(size 1.27 1.27)
					(thickness 0.15)
				)
				(justify left bottom)
				(hide yes)
			)
		)
		(property "Datasheet" "https://www.bourns.com/docs/product-datasheets/cr.pdf"
			(at 176.53 100.33 0)
			(effects
				(font
					(size 1.27 1.27)
					(thickness 0.15)
				)
				(justify left bottom)
				(hide yes)
			)
		)
		(property "Description" "SMD Chip Resistor, 1 kohm, ± 1%, 63 mW, 0402 [1005 Metric], Thick Film, General Purpose"
			(at 158.75 120.65 0)
			(effects
				(font
					(size 1.27 1.27)
				)
				(hide yes)
			)
		)
		(property "MPN" "CR0402-FX-1001GLF"
			(at 179.07 100.33 0)
			(effects
				(font
					(size 1.27 1.27)
					(thickness 0.15)
				)
				(justify left bottom)
				(hide yes)
			)
		)
		(property "Manufacturer" "Bourns"
			(at 181.61 100.33 0)
			(effects
				(font
					(size 1.27 1.27)
					(thickness 0.15)
				)
				(justify left bottom)
				(hide yes)
			)
		)
		(property "License" "Apache-2.0"
			(at 184.15 100.33 0)
			(effects
				(font
					(size 1.27 1.27)
					(thickness 0.15)
				)
				(justify left bottom)
				(hide yes)
			)
		)
		(property "Author" "Antmicro"
			(at 186.69 100.33 0)
			(effects
				(font
					(size 1.27 1.27)
					(thickness 0.15)
				)
				(justify left bottom)
				(hide yes)
			)
		)
		(property "Val" "1k"
			(at 160.02 119.38 90)
			(effects
				(font
					(size 1.27 1.27)
					(thickness 0.15)
				)
				(justify right)
			)
		)
		(property "Tolerance" "1%"
			(at 168.91 100.33 0)
			(effects
				(font
					(size 1.27 1.27)
				)
				(justify left bottom)
				(hide yes)
			)
		)
		(pin "2"
		)
		(pin "1"
		)
		(instances
			(project "jetson-agx-thor-baseboard"
				(path ""
					(reference "R189")
					(unit 1)
				)
			)
		)
	)
	(symbol
		(lib_id "antmicroCapacitors0603:C_22u_16V_0603")
		(at 156.21 99.06 90)
		(unit 1)
		(exclude_from_sim no)
		(in_bom yes)
		(on_board yes)
		(dnp no)
		(fields_autoplaced yes)
		(property "Reference" "C168"
			(at 158.75 95.2436 90)
			(effects
				(font
					(size 1.27 1.27)
					(thickness 0.15)
				)
				(justify right)
			)
		)
		(property "Value" "C_22u_16V_0603"
			(at 166.37 78.74 0)
			(effects
				(font
					(size 1.27 1.27)
					(thickness 0.15)
				)
				(justify left bottom)
				(hide yes)
			)
		)
		(property "Footprint" "antmicro-footprints:C_0603_1608Metric_EIA"
			(at 168.91 78.74 0)
			(effects
				(font
					(size 1.27 1.27)
					(thickness 0.15)
				)
				(justify left bottom)
				(hide yes)
			)
		)
		(property "Datasheet" "https://product.samsungsem.com/mlcc/CL10A226MO7JZN.do"
			(at 171.45 78.74 0)
			(effects
				(font
					(size 1.27 1.27)
					(thickness 0.15)
				)
				(justify left bottom)
				(hide yes)
			)
		)
		(property "Description" "SMD Multilayer Ceramic Capacitor"
			(at 156.21 99.06 0)
			(effects
				(font
					(size 1.27 1.27)
				)
				(hide yes)
			)
		)
		(property "MPN" "CL10A226MO7JZNC"
			(at 173.99 78.74 0)
			(effects
				(font
					(size 1.27 1.27)
					(thickness 0.15)
				)
				(justify left bottom)
				(hide yes)
			)
		)
		(property "Manufacturer" "Samsung Electro-Mechanics"
			(at 176.53 78.74 0)
			(effects
				(font
					(size 1.27 1.27)
					(thickness 0.15)
				)
				(justify left bottom)
				(hide yes)
			)
		)
		(property "License" "Apache-2.0"
			(at 179.07 78.74 0)
			(effects
				(font
					(size 1.27 1.27)
					(thickness 0.15)
				)
				(justify left bottom)
				(hide yes)
			)
		)
		(property "Author" "Antmicro"
			(at 181.61 78.74 0)
			(effects
				(font
					(size 1.27 1.27)
					(thickness 0.15)
				)
				(justify left bottom)
				(hide yes)
			)
		)
		(property "Val" "22u"
			(at 158.75 97.7836 90)
			(effects
				(font
					(size 1.27 1.27)
					(thickness 0.15)
				)
				(justify right)
			)
		)
		(property "Voltage" "16V"
			(at 184.15 78.74 0)
			(effects
				(font
					(size 1.27 1.27)
				)
				(justify left bottom)
				(hide yes)
			)
		)
		(property "Dielectric" ""
			(at 186.69 78.74 0)
			(effects
				(font
					(size 1.27 1.27)
				)
				(justify left bottom)
				(hide yes)
			)
		)
		(pin "1"
		)
		(pin "2"
		)
		(instances
			(project ""
				(path ""
					(reference "C168")
					(unit 1)
				)
			)
		)
	)
	(symbol
		(lib_id "antmicroCapacitors0402:C_100n_0402")
		(at 311.15 157.48 90)
		(unit 1)
		(exclude_from_sim no)
		(in_bom yes)
		(on_board yes)
		(dnp no)
		(fields_autoplaced yes)
		(property "Reference" "C179"
			(at 313.69 153.6636 90)
			(effects
				(font
					(size 1.27 1.27)
					(thickness 0.15)
				)
				(justify right)
			)
		)
		(property "Value" "C_100n_0402"
			(at 321.31 137.16 0)
			(effects
				(font
					(size 1.27 1.27)
					(thickness 0.15)
				)
				(justify left bottom)
				(hide yes)
			)
		)
		(property "Footprint" "antmicro-footprints:C_0402_1005Metric"
			(at 323.85 137.16 0)
			(effects
				(font
					(size 1.27 1.27)
					(thickness 0.15)
				)
				(justify left bottom)
				(hide yes)
			)
		)
		(property "Datasheet" "https://www.murata.com/products/productdetail?partno=GRM155R61H104KE14%23"
			(at 326.39 137.16 0)
			(effects
				(font
					(size 1.27 1.27)
					(thickness 0.15)
				)
				(justify left bottom)
				(hide yes)
			)
		)
		(property "Description" "SMD Multilayer Ceramic Capacitor, 0.1 µF, 50 V, 0402 [1005 Metric], ± 10%, X5R, GRM Series"
			(at 311.15 157.48 0)
			(effects
				(font
					(size 1.27 1.27)
				)
				(hide yes)
			)
		)
		(property "MPN" "GRM155R61H104KE14D"
			(at 328.93 137.16 0)
			(effects
				(font
					(size 1.27 1.27)
					(thickness 0.15)
				)
				(justify left bottom)
				(hide yes)
			)
		)
		(property "Manufacturer" "Murata"
			(at 331.47 137.16 0)
			(effects
				(font
					(size 1.27 1.27)
					(thickness 0.15)
				)
				(justify left bottom)
				(hide yes)
			)
		)
		(property "License" "Apache-2.0"
			(at 334.01 137.16 0)
			(effects
				(font
					(size 1.27 1.27)
					(thickness 0.15)
				)
				(justify left bottom)
				(hide yes)
			)
		)
		(property "Author" "Antmicro"
			(at 336.55 137.16 0)
			(effects
				(font
					(size 1.27 1.27)
					(thickness 0.15)
				)
				(justify left bottom)
				(hide yes)
			)
		)
		(property "Val" "100n"
			(at 313.69 156.2036 90)
			(effects
				(font
					(size 1.27 1.27)
					(thickness 0.15)
				)
				(justify right)
			)
		)
		(property "Voltage" "50V"
			(at 339.09 137.16 0)
			(effects
				(font
					(size 1.27 1.27)
				)
				(justify left bottom)
				(hide yes)
			)
		)
		(property "Dielectric" "X5R"
			(at 341.63 137.16 0)
			(effects
				(font
					(size 1.27 1.27)
				)
				(justify left bottom)
				(hide yes)
			)
		)
		(pin "2"
		)
		(pin "1"
		)
		(instances
			(project "jetson-agx-thor-baseboard"
				(path ""
					(reference "C179")
					(unit 1)
				)
			)
		)
	)
	(symbol
		(lib_id "antmicroResistors0402:R_1k_0402")
		(at 147.32 120.65 90)
		(unit 1)
		(exclude_from_sim no)
		(in_bom yes)
		(on_board yes)
		(dnp no)
		(property "Reference" "R197"
			(at 140.97 117.094 90)
			(effects
				(font
					(size 1.27 1.27)
					(thickness 0.15)
				)
				(justify right)
			)
		)
		(property "Value" "R_1k_0402"
			(at 160.02 100.33 0)
			(effects
				(font
					(size 1.27 1.27)
					(thickness 0.15)
				)
				(justify left bottom)
				(hide yes)
			)
		)
		(property "Footprint" "antmicro-footprints:R_0402_1005Metric"
			(at 162.56 100.33 0)
			(effects
				(font
					(size 1.27 1.27)
					(thickness 0.15)
				)
				(justify left bottom)
				(hide yes)
			)
		)
		(property "Datasheet" "https://www.bourns.com/docs/product-datasheets/cr.pdf"
			(at 165.1 100.33 0)
			(effects
				(font
					(size 1.27 1.27)
					(thickness 0.15)
				)
				(justify left bottom)
				(hide yes)
			)
		)
		(property "Description" "SMD Chip Resistor, 1 kohm, ± 1%, 63 mW, 0402 [1005 Metric], Thick Film, General Purpose"
			(at 147.32 120.65 0)
			(effects
				(font
					(size 1.27 1.27)
				)
				(hide yes)
			)
		)
		(property "MPN" "CR0402-FX-1001GLF"
			(at 167.64 100.33 0)
			(effects
				(font
					(size 1.27 1.27)
					(thickness 0.15)
				)
				(justify left bottom)
				(hide yes)
			)
		)
		(property "Manufacturer" "Bourns"
			(at 170.18 100.33 0)
			(effects
				(font
					(size 1.27 1.27)
					(thickness 0.15)
				)
				(justify left bottom)
				(hide yes)
			)
		)
		(property "License" "Apache-2.0"
			(at 172.72 100.33 0)
			(effects
				(font
					(size 1.27 1.27)
					(thickness 0.15)
				)
				(justify left bottom)
				(hide yes)
			)
		)
		(property "Author" "Antmicro"
			(at 175.26 100.33 0)
			(effects
				(font
					(size 1.27 1.27)
					(thickness 0.15)
				)
				(justify left bottom)
				(hide yes)
			)
		)
		(property "Val" "1k"
			(at 143.764 119.126 90)
			(effects
				(font
					(size 1.27 1.27)
					(thickness 0.15)
				)
				(justify right)
			)
		)
		(property "Tolerance" "1%"
			(at 157.48 100.33 0)
			(effects
				(font
					(size 1.27 1.27)
				)
				(justify left bottom)
				(hide yes)
			)
		)
		(pin "2"
		)
		(pin "1"
		)
		(instances
			(project "jetson-agx-thor-baseboard"
				(path ""
					(reference "R197")
					(unit 1)
				)
			)
		)
	)
	(symbol
		(lib_id "antmicropower:GND")
		(at 293.37 162.56 0)
		(mirror y)
		(unit 1)
		(exclude_from_sim no)
		(in_bom yes)
		(on_board yes)
		(dnp no)
		(property "Reference" "#PWR0358"
			(at 284.48 165.1 0)
			(effects
				(font
					(size 1.27 1.27)
					(thickness 0.15)
				)
				(justify left bottom)
				(hide yes)
			)
		)
		(property "Value" "GND"
			(at 293.37 166.37 0)
			(effects
				(font
					(size 1.27 1.27)
					(thickness 0.15)
				)
			)
		)
		(property "Footprint" ""
			(at 284.48 170.18 0)
			(effects
				(font
					(size 1.27 1.27)
					(thickness 0.15)
				)
				(justify left bottom)
				(hide yes)
			)
		)
		(property "Datasheet" ""
			(at 284.48 175.26 0)
			(effects
				(font
					(size 1.27 1.27)
					(thickness 0.15)
				)
				(justify left bottom)
				(hide yes)
			)
		)
		(property "Description" ""
			(at 293.37 162.56 0)
			(effects
				(font
					(size 1.27 1.27)
				)
				(hide yes)
			)
		)
		(property "Author" "Antmicro"
			(at 284.48 170.18 0)
			(effects
				(font
					(size 1.27 1.27)
					(thickness 0.15)
				)
				(justify left bottom)
				(hide yes)
			)
		)
		(property "License" "Apache-2.0"
			(at 284.48 172.72 0)
			(effects
				(font
					(size 1.27 1.27)
					(thickness 0.15)
				)
				(justify left bottom)
				(hide yes)
			)
		)
		(pin "1"
		)
		(instances
			(project "jetson-agx-thor-baseboard"
				(path ""
					(reference "#PWR0358")
					(unit 1)
				)
			)
		)
	)
	(symbol
		(lib_id "antmicroCapacitors0402:C_100n_0402")
		(at 173.99 99.06 90)
		(unit 1)
		(exclude_from_sim no)
		(in_bom yes)
		(on_board yes)
		(dnp no)
		(fields_autoplaced yes)
		(property "Reference" "C171"
			(at 176.53 95.2436 90)
			(effects
				(font
					(size 1.27 1.27)
					(thickness 0.15)
				)
				(justify right)
			)
		)
		(property "Value" "C_100n_0402"
			(at 184.15 78.74 0)
			(effects
				(font
					(size 1.27 1.27)
					(thickness 0.15)
				)
				(justify left bottom)
				(hide yes)
			)
		)
		(property "Footprint" "antmicro-footprints:C_0402_1005Metric"
			(at 186.69 78.74 0)
			(effects
				(font
					(size 1.27 1.27)
					(thickness 0.15)
				)
				(justify left bottom)
				(hide yes)
			)
		)
		(property "Datasheet" "https://www.murata.com/products/productdetail?partno=GRM155R61H104KE14%23"
			(at 189.23 78.74 0)
			(effects
				(font
					(size 1.27 1.27)
					(thickness 0.15)
				)
				(justify left bottom)
				(hide yes)
			)
		)
		(property "Description" "SMD Multilayer Ceramic Capacitor, 0.1 µF, 50 V, 0402 [1005 Metric], ± 10%, X5R, GRM Series"
			(at 173.99 99.06 0)
			(effects
				(font
					(size 1.27 1.27)
				)
				(hide yes)
			)
		)
		(property "MPN" "GRM155R61H104KE14D"
			(at 191.77 78.74 0)
			(effects
				(font
					(size 1.27 1.27)
					(thickness 0.15)
				)
				(justify left bottom)
				(hide yes)
			)
		)
		(property "Manufacturer" "Murata"
			(at 194.31 78.74 0)
			(effects
				(font
					(size 1.27 1.27)
					(thickness 0.15)
				)
				(justify left bottom)
				(hide yes)
			)
		)
		(property "License" "Apache-2.0"
			(at 196.85 78.74 0)
			(effects
				(font
					(size 1.27 1.27)
					(thickness 0.15)
				)
				(justify left bottom)
				(hide yes)
			)
		)
		(property "Author" "Antmicro"
			(at 199.39 78.74 0)
			(effects
				(font
					(size 1.27 1.27)
					(thickness 0.15)
				)
				(justify left bottom)
				(hide yes)
			)
		)
		(property "Val" "100n"
			(at 176.53 97.7836 90)
			(effects
				(font
					(size 1.27 1.27)
					(thickness 0.15)
				)
				(justify right)
			)
		)
		(property "Voltage" "50V"
			(at 201.93 78.74 0)
			(effects
				(font
					(size 1.27 1.27)
				)
				(justify left bottom)
				(hide yes)
			)
		)
		(property "Dielectric" "X5R"
			(at 204.47 78.74 0)
			(effects
				(font
					(size 1.27 1.27)
				)
				(justify left bottom)
				(hide yes)
			)
		)
		(pin "2"
		)
		(pin "1"
		)
		(instances
			(project ""
				(path ""
					(reference "C171")
					(unit 1)
				)
			)
		)
	)
	(symbol
		(lib_id "antmicropower:GND")
		(at 212.09 162.56 0)
		(unit 1)
		(exclude_from_sim no)
		(in_bom yes)
		(on_board yes)
		(dnp no)
		(property "Reference" "#PWR0349"
			(at 220.98 165.1 0)
			(effects
				(font
					(size 1.27 1.27)
					(thickness 0.15)
				)
				(justify left bottom)
				(hide yes)
			)
		)
		(property "Value" "GND"
			(at 212.09 166.37 0)
			(effects
				(font
					(size 1.27 1.27)
					(thickness 0.15)
				)
			)
		)
		(property "Footprint" ""
			(at 220.98 170.18 0)
			(effects
				(font
					(size 1.27 1.27)
					(thickness 0.15)
				)
				(justify left bottom)
				(hide yes)
			)
		)
		(property "Datasheet" ""
			(at 220.98 175.26 0)
			(effects
				(font
					(size 1.27 1.27)
					(thickness 0.15)
				)
				(justify left bottom)
				(hide yes)
			)
		)
		(property "Description" ""
			(at 212.09 162.56 0)
			(effects
				(font
					(size 1.27 1.27)
				)
				(hide yes)
			)
		)
		(property "Author" "Antmicro"
			(at 220.98 170.18 0)
			(effects
				(font
					(size 1.27 1.27)
					(thickness 0.15)
				)
				(justify left bottom)
				(hide yes)
			)
		)
		(property "License" "Apache-2.0"
			(at 220.98 172.72 0)
			(effects
				(font
					(size 1.27 1.27)
					(thickness 0.15)
				)
				(justify left bottom)
				(hide yes)
			)
		)
		(pin "1"
		)
		(instances
			(project "jetson-agx-thor-baseboard"
				(path ""
					(reference "#PWR0349")
					(unit 1)
				)
			)
		)
	)
	(symbol
		(lib_id "antmicropower:GND")
		(at 275.59 162.56 0)
		(mirror y)
		(unit 1)
		(exclude_from_sim no)
		(in_bom yes)
		(on_board yes)
		(dnp no)
		(property "Reference" "#PWR0355"
			(at 266.7 165.1 0)
			(effects
				(font
					(size 1.27 1.27)
					(thickness 0.15)
				)
				(justify left bottom)
				(hide yes)
			)
		)
		(property "Value" "GND"
			(at 275.59 166.37 0)
			(effects
				(font
					(size 1.27 1.27)
					(thickness 0.15)
				)
			)
		)
		(property "Footprint" ""
			(at 266.7 170.18 0)
			(effects
				(font
					(size 1.27 1.27)
					(thickness 0.15)
				)
				(justify left bottom)
				(hide yes)
			)
		)
		(property "Datasheet" ""
			(at 266.7 175.26 0)
			(effects
				(font
					(size 1.27 1.27)
					(thickness 0.15)
				)
				(justify left bottom)
				(hide yes)
			)
		)
		(property "Description" ""
			(at 275.59 162.56 0)
			(effects
				(font
					(size 1.27 1.27)
				)
				(hide yes)
			)
		)
		(property "Author" "Antmicro"
			(at 266.7 170.18 0)
			(effects
				(font
					(size 1.27 1.27)
					(thickness 0.15)
				)
				(justify left bottom)
				(hide yes)
			)
		)
		(property "License" "Apache-2.0"
			(at 266.7 172.72 0)
			(effects
				(font
					(size 1.27 1.27)
					(thickness 0.15)
				)
				(justify left bottom)
				(hide yes)
			)
		)
		(pin "1"
		)
		(instances
			(project "jetson-agx-thor-baseboard"
				(path ""
					(reference "#PWR0355")
					(unit 1)
				)
			)
		)
	)
	(symbol
		(lib_id "antmicroTVSDiodes:TPD4E05U06QDQARQ1")
		(at 242.57 116.84 0)
		(unit 1)
		(exclude_from_sim no)
		(in_bom yes)
		(on_board yes)
		(dnp no)
		(property "Reference" "U73"
			(at 244.856 113.03 0)
			(effects
				(font
					(size 1.27 1.27)
				)
				(justify left)
			)
		)
		(property "Value" "TPD4E05U06QDQARQ1"
			(at 266.7 127 0)
			(effects
				(font
					(size 1.27 1.27)
					(thickness 0.15)
				)
				(justify left bottom)
				(hide yes)
			)
		)
		(property "Footprint" "antmicro-footprints:USON-10_2.5x1mm_P0.5mm"
			(at 266.7 121.92 0)
			(effects
				(font
					(size 1.27 1.27)
					(thickness 0.15)
				)
				(justify left bottom)
				(hide yes)
			)
		)
		(property "Datasheet" "https://www.ti.com/lit/ds/symlink/tpd4e05u06-q1.pdf?HQS=dis-mous-null-mousermode-dsf-pf-null-wwe&ts=1663591265741&ref_url=https%253A%252F%252Fwww.mouser.com%252F"
			(at 266.7 124.46 0)
			(effects
				(font
					(size 1.27 1.27)
					(thickness 0.15)
				)
				(justify left bottom)
				(hide yes)
			)
		)
		(property "Description" "TVS diode array, 12 kV, USON-10, 5.5 V, 0.5 pF"
			(at 242.57 116.84 0)
			(effects
				(font
					(size 1.27 1.27)
				)
				(hide yes)
			)
		)
		(property "Manufacturer" "Texas Instruments"
			(at 266.7 129.54 0)
			(effects
				(font
					(size 1.27 1.27)
					(thickness 0.15)
				)
				(justify left bottom)
				(hide yes)
			)
		)
		(property "MPN" "TPD4E05U06QDQARQ1"
			(at 242.57 130.048 0)
			(effects
				(font
					(size 1.27 1.27)
					(thickness 0.15)
				)
				(justify left)
			)
		)
		(property "Author" "Antmicro"
			(at 266.7 132.08 0)
			(effects
				(font
					(size 1.27 1.27)
					(thickness 0.15)
				)
				(justify left bottom)
				(hide yes)
			)
		)
		(property "License" "Apache-2.0"
			(at 266.7 134.62 0)
			(effects
				(font
					(size 1.27 1.27)
					(thickness 0.15)
				)
				(justify left bottom)
				(hide yes)
			)
		)
		(pin "1"
		)
		(pin "10"
		)
		(pin "2"
		)
		(pin "3"
		)
		(pin "4"
		)
		(pin "5"
		)
		(pin "6"
		)
		(pin "7"
		)
		(pin "8"
		)
		(pin "9"
		)
		(instances
			(project "jetson-agx-thor-baseboard"
				(path ""
					(reference "U73")
					(unit 1)
				)
			)
		)
	)
	(symbol
		(lib_id "antmicropower:GND")
		(at 173.99 100.33 0)
		(mirror y)
		(unit 1)
		(exclude_from_sim no)
		(in_bom yes)
		(on_board yes)
		(dnp no)
		(property "Reference" "#PWR0347"
			(at 165.1 102.87 0)
			(effects
				(font
					(size 1.27 1.27)
					(thickness 0.15)
				)
				(justify left bottom)
				(hide yes)
			)
		)
		(property "Value" "GND"
			(at 173.99 104.14 0)
			(effects
				(font
					(size 1.27 1.27)
					(thickness 0.15)
				)
			)
		)
		(property "Footprint" ""
			(at 165.1 107.95 0)
			(effects
				(font
					(size 1.27 1.27)
					(thickness 0.15)
				)
				(justify left bottom)
				(hide yes)
			)
		)
		(property "Datasheet" ""
			(at 165.1 113.03 0)
			(effects
				(font
					(size 1.27 1.27)
					(thickness 0.15)
				)
				(justify left bottom)
				(hide yes)
			)
		)
		(property "Description" ""
			(at 173.99 100.33 0)
			(effects
				(font
					(size 1.27 1.27)
				)
				(hide yes)
			)
		)
		(property "Author" "Antmicro"
			(at 165.1 107.95 0)
			(effects
				(font
					(size 1.27 1.27)
					(thickness 0.15)
				)
				(justify left bottom)
				(hide yes)
			)
		)
		(property "License" "Apache-2.0"
			(at 165.1 110.49 0)
			(effects
				(font
					(size 1.27 1.27)
					(thickness 0.15)
				)
				(justify left bottom)
				(hide yes)
			)
		)
		(pin "1"
		)
		(instances
			(project "jetson-agx-thor-baseboard"
				(path ""
					(reference "#PWR0347")
					(unit 1)
				)
			)
		)
	)
	(symbol
		(lib_id "antmicropower:GND")
		(at 257.81 162.56 0)
		(mirror y)
		(unit 1)
		(exclude_from_sim no)
		(in_bom yes)
		(on_board yes)
		(dnp no)
		(property "Reference" "#PWR0352"
			(at 248.92 165.1 0)
			(effects
				(font
					(size 1.27 1.27)
					(thickness 0.15)
				)
				(justify left bottom)
				(hide yes)
			)
		)
		(property "Value" "GND"
			(at 257.81 166.37 0)
			(effects
				(font
					(size 1.27 1.27)
					(thickness 0.15)
				)
			)
		)
		(property "Footprint" ""
			(at 248.92 170.18 0)
			(effects
				(font
					(size 1.27 1.27)
					(thickness 0.15)
				)
				(justify left bottom)
				(hide yes)
			)
		)
		(property "Datasheet" ""
			(at 248.92 175.26 0)
			(effects
				(font
					(size 1.27 1.27)
					(thickness 0.15)
				)
				(justify left bottom)
				(hide yes)
			)
		)
		(property "Description" ""
			(at 257.81 162.56 0)
			(effects
				(font
					(size 1.27 1.27)
				)
				(hide yes)
			)
		)
		(property "Author" "Antmicro"
			(at 248.92 170.18 0)
			(effects
				(font
					(size 1.27 1.27)
					(thickness 0.15)
				)
				(justify left bottom)
				(hide yes)
			)
		)
		(property "License" "Apache-2.0"
			(at 248.92 172.72 0)
			(effects
				(font
					(size 1.27 1.27)
					(thickness 0.15)
				)
				(justify left bottom)
				(hide yes)
			)
		)
		(pin "1"
		)
		(instances
			(project "jetson-agx-thor-baseboard"
				(path ""
					(reference "#PWR0352")
					(unit 1)
				)
			)
		)
	)
	(symbol
		(lib_id "antmicropower:GND")
		(at 165.1 142.24 0)
		(unit 1)
		(exclude_from_sim no)
		(in_bom yes)
		(on_board yes)
		(dnp no)
		(property "Reference" "#PWR0344"
			(at 173.99 144.78 0)
			(effects
				(font
					(size 1.27 1.27)
					(thickness 0.15)
				)
				(justify left bottom)
				(hide yes)
			)
		)
		(property "Value" "GND"
			(at 161.29 143.51 0)
			(effects
				(font
					(size 1.27 1.27)
					(thickness 0.15)
				)
			)
		)
		(property "Footprint" ""
			(at 173.99 149.86 0)
			(effects
				(font
					(size 1.27 1.27)
					(thickness 0.15)
				)
				(justify left bottom)
				(hide yes)
			)
		)
		(property "Datasheet" ""
			(at 173.99 154.94 0)
			(effects
				(font
					(size 1.27 1.27)
					(thickness 0.15)
				)
				(justify left bottom)
				(hide yes)
			)
		)
		(property "Description" ""
			(at 165.1 142.24 0)
			(effects
				(font
					(size 1.27 1.27)
				)
				(hide yes)
			)
		)
		(property "Author" "Antmicro"
			(at 173.99 149.86 0)
			(effects
				(font
					(size 1.27 1.27)
					(thickness 0.15)
				)
				(justify left bottom)
				(hide yes)
			)
		)
		(property "License" "Apache-2.0"
			(at 173.99 152.4 0)
			(effects
				(font
					(size 1.27 1.27)
					(thickness 0.15)
				)
				(justify left bottom)
				(hide yes)
			)
		)
		(pin "1"
		)
		(instances
			(project "jetson-agx-thor-baseboard"
				(path ""
					(reference "#PWR0344")
					(unit 1)
				)
			)
		)
	)
	(symbol
		(lib_id "antmicropower:GND")
		(at 165.1 100.33 0)
		(mirror y)
		(unit 1)
		(exclude_from_sim no)
		(in_bom yes)
		(on_board yes)
		(dnp no)
		(property "Reference" "#PWR0343"
			(at 156.21 102.87 0)
			(effects
				(font
					(size 1.27 1.27)
					(thickness 0.15)
				)
				(justify left bottom)
				(hide yes)
			)
		)
		(property "Value" "GND"
			(at 165.1 104.14 0)
			(effects
				(font
					(size 1.27 1.27)
					(thickness 0.15)
				)
			)
		)
		(property "Footprint" ""
			(at 156.21 107.95 0)
			(effects
				(font
					(size 1.27 1.27)
					(thickness 0.15)
				)
				(justify left bottom)
				(hide yes)
			)
		)
		(property "Datasheet" ""
			(at 156.21 113.03 0)
			(effects
				(font
					(size 1.27 1.27)
					(thickness 0.15)
				)
				(justify left bottom)
				(hide yes)
			)
		)
		(property "Description" ""
			(at 165.1 100.33 0)
			(effects
				(font
					(size 1.27 1.27)
				)
				(hide yes)
			)
		)
		(property "Author" "Antmicro"
			(at 156.21 107.95 0)
			(effects
				(font
					(size 1.27 1.27)
					(thickness 0.15)
				)
				(justify left bottom)
				(hide yes)
			)
		)
		(property "License" "Apache-2.0"
			(at 156.21 110.49 0)
			(effects
				(font
					(size 1.27 1.27)
					(thickness 0.15)
				)
				(justify left bottom)
				(hide yes)
			)
		)
		(pin "1"
		)
		(instances
			(project "jetson-agx-thor-baseboard"
				(path ""
					(reference "#PWR0343")
					(unit 1)
				)
			)
		)
	)
	(symbol
		(lib_id "antmicroResistors0402:R_200R_0402")
		(at 285.75 128.27 90)
		(unit 1)
		(exclude_from_sim no)
		(in_bom yes)
		(on_board yes)
		(dnp no)
		(fields_autoplaced yes)
		(property "Reference" "R204"
			(at 288.29 124.46 90)
			(effects
				(font
					(size 1.27 1.27)
				)
				(justify right)
			)
		)
		(property "Value" "R_200R_0402"
			(at 298.45 107.95 0)
			(effects
				(font
					(size 1.27 1.27)
					(thickness 0.15)
				)
				(justify left bottom)
				(hide yes)
			)
		)
		(property "Footprint" "antmicro-footprints:R_0402_1005Metric"
			(at 300.99 107.95 0)
			(effects
				(font
					(size 1.27 1.27)
					(thickness 0.15)
				)
				(justify left bottom)
				(hide yes)
			)
		)
		(property "Datasheet" "https://www.bourns.com/docs/product-datasheets/cr.pdf"
			(at 303.53 107.95 0)
			(effects
				(font
					(size 1.27 1.27)
					(thickness 0.15)
				)
				(justify left bottom)
				(hide yes)
			)
		)
		(property "Description" "SMD Chip Resistor, 200 ohm, ± 1%, 62.5 mW, 0402 [1005 Metric], Thick Film, General Purpose"
			(at 285.75 128.27 0)
			(effects
				(font
					(size 1.27 1.27)
				)
				(hide yes)
			)
		)
		(property "Manufacturer" "Bourns"
			(at 308.61 107.95 0)
			(effects
				(font
					(size 1.27 1.27)
					(thickness 0.15)
				)
				(justify left bottom)
				(hide yes)
			)
		)
		(property "MPN" "CR0402-FX-2000GLF"
			(at 306.07 107.95 0)
			(effects
				(font
					(size 1.27 1.27)
					(thickness 0.15)
				)
				(justify left bottom)
				(hide yes)
			)
		)
		(property "Val" "200R"
			(at 288.29 127 90)
			(effects
				(font
					(size 1.27 1.27)
					(thickness 0.15)
				)
				(justify right)
			)
		)
		(property "License" "Apache-2.0"
			(at 311.15 107.95 0)
			(effects
				(font
					(size 1.27 1.27)
					(thickness 0.15)
				)
				(justify left bottom)
				(hide yes)
			)
		)
		(property "Author" "Antmicro"
			(at 313.69 107.95 0)
			(effects
				(font
					(size 1.27 1.27)
					(thickness 0.15)
				)
				(justify left bottom)
				(hide yes)
			)
		)
		(property "Tolerance" "1%"
			(at 295.91 107.95 0)
			(effects
				(font
					(size 1.27 1.27)
				)
				(justify left bottom)
				(hide yes)
			)
		)
		(pin "1"
		)
		(pin "2"
		)
		(instances
			(project "jetson-agx-thor-baseboard"
				(path ""
					(reference "R204")
					(unit 1)
				)
			)
		)
	)
	(symbol
		(lib_id "antmicropower:GND")
		(at 241.3 128.27 0)
		(unit 1)
		(exclude_from_sim no)
		(in_bom yes)
		(on_board yes)
		(dnp no)
		(property "Reference" "#PWR0648"
			(at 241.3 134.62 0)
			(effects
				(font
					(size 1.27 1.27)
				)
				(justify left bottom)
				(hide yes)
			)
		)
		(property "Value" "GND"
			(at 241.3 132.08 0)
			(effects
				(font
					(size 1.27 1.27)
					(thickness 0.15)
				)
			)
		)
		(property "Footprint" ""
			(at 250.19 135.89 0)
			(effects
				(font
					(size 1.27 1.27)
					(thickness 0.15)
				)
				(justify left bottom)
				(hide yes)
			)
		)
		(property "Datasheet" ""
			(at 250.19 140.97 0)
			(effects
				(font
					(size 1.27 1.27)
					(thickness 0.15)
				)
				(justify left bottom)
				(hide yes)
			)
		)
		(property "Description" ""
			(at 241.3 128.27 0)
			(effects
				(font
					(size 1.27 1.27)
				)
				(hide yes)
			)
		)
		(property "Author" "Antmicro"
			(at 250.19 135.89 0)
			(effects
				(font
					(size 1.27 1.27)
					(thickness 0.15)
				)
				(justify left bottom)
				(hide yes)
			)
		)
		(property "License" "Apache-2.0"
			(at 250.19 138.43 0)
			(effects
				(font
					(size 1.27 1.27)
					(thickness 0.15)
				)
				(justify left bottom)
				(hide yes)
			)
		)
		(pin "1"
		)
		(instances
			(project "jetson-agx-thor-baseboard"
				(path ""
					(reference "#PWR0648")
					(unit 1)
				)
			)
		)
	)
	(symbol
		(lib_id "antmicroCapacitors0402:C_100n_0402")
		(at 248.92 157.48 90)
		(unit 1)
		(exclude_from_sim no)
		(in_bom yes)
		(on_board yes)
		(dnp no)
		(fields_autoplaced yes)
		(property "Reference" "C172"
			(at 251.46 153.6636 90)
			(effects
				(font
					(size 1.27 1.27)
					(thickness 0.15)
				)
				(justify right)
			)
		)
		(property "Value" "C_100n_0402"
			(at 259.08 137.16 0)
			(effects
				(font
					(size 1.27 1.27)
					(thickness 0.15)
				)
				(justify left bottom)
				(hide yes)
			)
		)
		(property "Footprint" "antmicro-footprints:C_0402_1005Metric"
			(at 261.62 137.16 0)
			(effects
				(font
					(size 1.27 1.27)
					(thickness 0.15)
				)
				(justify left bottom)
				(hide yes)
			)
		)
		(property "Datasheet" "https://www.murata.com/products/productdetail?partno=GRM155R61H104KE14%23"
			(at 264.16 137.16 0)
			(effects
				(font
					(size 1.27 1.27)
					(thickness 0.15)
				)
				(justify left bottom)
				(hide yes)
			)
		)
		(property "Description" "SMD Multilayer Ceramic Capacitor, 0.1 µF, 50 V, 0402 [1005 Metric], ± 10%, X5R, GRM Series"
			(at 248.92 157.48 0)
			(effects
				(font
					(size 1.27 1.27)
				)
				(hide yes)
			)
		)
		(property "MPN" "GRM155R61H104KE14D"
			(at 266.7 137.16 0)
			(effects
				(font
					(size 1.27 1.27)
					(thickness 0.15)
				)
				(justify left bottom)
				(hide yes)
			)
		)
		(property "Manufacturer" "Murata"
			(at 269.24 137.16 0)
			(effects
				(font
					(size 1.27 1.27)
					(thickness 0.15)
				)
				(justify left bottom)
				(hide yes)
			)
		)
		(property "License" "Apache-2.0"
			(at 271.78 137.16 0)
			(effects
				(font
					(size 1.27 1.27)
					(thickness 0.15)
				)
				(justify left bottom)
				(hide yes)
			)
		)
		(property "Author" "Antmicro"
			(at 274.32 137.16 0)
			(effects
				(font
					(size 1.27 1.27)
					(thickness 0.15)
				)
				(justify left bottom)
				(hide yes)
			)
		)
		(property "Val" "100n"
			(at 251.46 156.2036 90)
			(effects
				(font
					(size 1.27 1.27)
					(thickness 0.15)
				)
				(justify right)
			)
		)
		(property "Voltage" "50V"
			(at 276.86 137.16 0)
			(effects
				(font
					(size 1.27 1.27)
				)
				(justify left bottom)
				(hide yes)
			)
		)
		(property "Dielectric" "X5R"
			(at 279.4 137.16 0)
			(effects
				(font
					(size 1.27 1.27)
				)
				(justify left bottom)
				(hide yes)
			)
		)
		(pin "2"
		)
		(pin "1"
		)
		(instances
			(project "jetson-agx-thor-baseboard"
				(path ""
					(reference "C172")
					(unit 1)
				)
			)
		)
	)
	(symbol
		(lib_id "antmicroResistors0402:R_0R_0402")
		(at 175.26 143.51 0)
		(unit 1)
		(exclude_from_sim no)
		(in_bom yes)
		(on_board yes)
		(dnp no)
		(property "Reference" "R199"
			(at 172.974 142.24 0)
			(effects
				(font
					(size 1.27 1.27)
					(thickness 0.15)
				)
			)
		)
		(property "Value" "R_0R_0402"
			(at 195.58 156.21 0)
			(effects
				(font
					(size 1.27 1.27)
					(thickness 0.15)
				)
				(justify left bottom)
				(hide yes)
			)
		)
		(property "Footprint" "antmicro-footprints:R_0402_1005Metric"
			(at 195.58 158.75 0)
			(effects
				(font
					(size 1.27 1.27)
					(thickness 0.15)
				)
				(justify left bottom)
				(hide yes)
			)
		)
		(property "Datasheet" "https://industrial.panasonic.com/cdbs/www-data/pdf/RDA0000/AOA0000C301.pdf"
			(at 195.58 161.29 0)
			(effects
				(font
					(size 1.27 1.27)
					(thickness 0.15)
				)
				(justify left bottom)
				(hide yes)
			)
		)
		(property "Description" "SMD Chip Resistor, Jumper, 0 ohm, 100 mW, 0402 [1005 Metric], Thick Film, General Purpose"
			(at 175.26 143.51 0)
			(effects
				(font
					(size 1.27 1.27)
				)
				(hide yes)
			)
		)
		(property "MPN" "ERJ2GE0R00X"
			(at 195.58 163.83 0)
			(effects
				(font
					(size 1.27 1.27)
					(thickness 0.15)
				)
				(justify left bottom)
				(hide yes)
			)
		)
		(property "Manufacturer" "Panasonic"
			(at 195.58 166.37 0)
			(effects
				(font
					(size 1.27 1.27)
					(thickness 0.15)
				)
				(justify left bottom)
				(hide yes)
			)
		)
		(property "License" "Apache-2.0"
			(at 195.58 168.91 0)
			(effects
				(font
					(size 1.27 1.27)
					(thickness 0.15)
				)
				(justify left bottom)
				(hide yes)
			)
		)
		(property "Author" "Antmicro"
			(at 195.58 171.45 0)
			(effects
				(font
					(size 1.27 1.27)
					(thickness 0.15)
				)
				(justify left bottom)
				(hide yes)
			)
		)
		(property "Val" "0R"
			(at 181.356 142.24 0)
			(effects
				(font
					(size 1.27 1.27)
					(thickness 0.15)
				)
			)
		)
		(property "Tolerance" "~"
			(at 195.58 153.67 0)
			(effects
				(font
					(size 1.27 1.27)
				)
				(justify left bottom)
				(hide yes)
			)
		)
		(property "Current" "1A"
			(at 195.58 173.99 0)
			(effects
				(font
					(size 1.27 1.27)
					(thickness 0.15)
				)
				(justify left bottom)
				(hide yes)
			)
		)
		(pin "1"
		)
		(pin "2"
		)
		(instances
			(project "jetson-agx-thor-baseboard"
				(path ""
					(reference "R199")
					(unit 1)
				)
			)
		)
	)
	(symbol
		(lib_id "antmicroCapacitors0402:C_100n_0402")
		(at 284.48 157.48 90)
		(unit 1)
		(exclude_from_sim no)
		(in_bom yes)
		(on_board yes)
		(dnp no)
		(fields_autoplaced yes)
		(property "Reference" "C176"
			(at 287.02 153.6636 90)
			(effects
				(font
					(size 1.27 1.27)
					(thickness 0.15)
				)
				(justify right)
			)
		)
		(property "Value" "C_100n_0402"
			(at 294.64 137.16 0)
			(effects
				(font
					(size 1.27 1.27)
					(thickness 0.15)
				)
				(justify left bottom)
				(hide yes)
			)
		)
		(property "Footprint" "antmicro-footprints:C_0402_1005Metric"
			(at 297.18 137.16 0)
			(effects
				(font
					(size 1.27 1.27)
					(thickness 0.15)
				)
				(justify left bottom)
				(hide yes)
			)
		)
		(property "Datasheet" "https://www.murata.com/products/productdetail?partno=GRM155R61H104KE14%23"
			(at 299.72 137.16 0)
			(effects
				(font
					(size 1.27 1.27)
					(thickness 0.15)
				)
				(justify left bottom)
				(hide yes)
			)
		)
		(property "Description" "SMD Multilayer Ceramic Capacitor, 0.1 µF, 50 V, 0402 [1005 Metric], ± 10%, X5R, GRM Series"
			(at 284.48 157.48 0)
			(effects
				(font
					(size 1.27 1.27)
				)
				(hide yes)
			)
		)
		(property "MPN" "GRM155R61H104KE14D"
			(at 302.26 137.16 0)
			(effects
				(font
					(size 1.27 1.27)
					(thickness 0.15)
				)
				(justify left bottom)
				(hide yes)
			)
		)
		(property "Manufacturer" "Murata"
			(at 304.8 137.16 0)
			(effects
				(font
					(size 1.27 1.27)
					(thickness 0.15)
				)
				(justify left bottom)
				(hide yes)
			)
		)
		(property "License" "Apache-2.0"
			(at 307.34 137.16 0)
			(effects
				(font
					(size 1.27 1.27)
					(thickness 0.15)
				)
				(justify left bottom)
				(hide yes)
			)
		)
		(property "Author" "Antmicro"
			(at 309.88 137.16 0)
			(effects
				(font
					(size 1.27 1.27)
					(thickness 0.15)
				)
				(justify left bottom)
				(hide yes)
			)
		)
		(property "Val" "100n"
			(at 287.02 156.2036 90)
			(effects
				(font
					(size 1.27 1.27)
					(thickness 0.15)
				)
				(justify right)
			)
		)
		(property "Voltage" "50V"
			(at 312.42 137.16 0)
			(effects
				(font
					(size 1.27 1.27)
				)
				(justify left bottom)
				(hide yes)
			)
		)
		(property "Dielectric" "X5R"
			(at 314.96 137.16 0)
			(effects
				(font
					(size 1.27 1.27)
				)
				(justify left bottom)
				(hide yes)
			)
		)
		(pin "2"
		)
		(pin "1"
		)
		(instances
			(project "jetson-agx-thor-baseboard"
				(path ""
					(reference "C176")
					(unit 1)
				)
			)
		)
	)
	(symbol
		(lib_id "antmicropower:+3V3")
		(at 156.21 91.44 0)
		(unit 1)
		(exclude_from_sim no)
		(in_bom yes)
		(on_board yes)
		(dnp no)
		(fields_autoplaced yes)
		(property "Reference" "#PWR0339"
			(at 171.45 91.44 0)
			(effects
				(font
					(size 1.27 1.27)
					(thickness 0.15)
				)
				(justify left bottom)
				(hide yes)
			)
		)
		(property "Value" "+3V3"
			(at 156.21 86.36 0)
			(effects
				(font
					(size 1.27 1.27)
					(thickness 0.15)
				)
			)
		)
		(property "Footprint" ""
			(at 171.45 99.06 0)
			(effects
				(font
					(size 1.27 1.27)
					(thickness 0.15)
				)
				(justify left bottom)
				(hide yes)
			)
		)
		(property "Datasheet" ""
			(at 171.45 101.6 0)
			(effects
				(font
					(size 1.27 1.27)
					(thickness 0.15)
				)
				(justify left bottom)
				(hide yes)
			)
		)
		(property "Description" ""
			(at 156.21 91.44 0)
			(effects
				(font
					(size 1.27 1.27)
				)
				(hide yes)
			)
		)
		(property "Author" "Antmicro"
			(at 171.45 93.98 0)
			(effects
				(font
					(size 1.27 1.27)
					(thickness 0.15)
				)
				(justify left bottom)
				(hide yes)
			)
		)
		(property "License" "Apache-2.0"
			(at 171.45 96.52 0)
			(effects
				(font
					(size 1.27 1.27)
					(thickness 0.15)
				)
				(justify left bottom)
				(hide yes)
			)
		)
		(pin "1"
		)
		(instances
			(project "jetson-agx-thor-baseboard"
				(path ""
					(reference "#PWR0339")
					(unit 1)
				)
			)
		)
	)
	(symbol
		(lib_id "antmicroTestPoints:TP_0.75mm_SMD")
		(at 165.1 135.89 0)
		(mirror y)
		(unit 1)
		(exclude_from_sim no)
		(in_bom no)
		(on_board yes)
		(dnp no)
		(property "Reference" "TP29"
			(at 157.988 135.89 0)
			(effects
				(font
					(size 1.27 1.27)
					(thickness 0.15)
				)
				(justify left)
			)
		)
		(property "Value" "TP_0.75mm_SMD"
			(at 154.94 139.7 0)
			(effects
				(font
					(size 1.27 1.27)
					(thickness 0.15)
				)
				(justify left bottom)
				(hide yes)
			)
		)
		(property "Footprint" "antmicro-footprints:TP_SMD_0.75mm"
			(at 154.94 142.24 0)
			(effects
				(font
					(size 1.27 1.27)
					(thickness 0.15)
				)
				(justify left bottom)
				(hide yes)
			)
		)
		(property "Datasheet" ""
			(at 147.32 148.59 0)
			(effects
				(font
					(size 1.27 1.27)
					(thickness 0.15)
				)
				(justify left bottom)
				(hide yes)
			)
		)
		(property "Description" "SMT test point"
			(at 165.1 135.89 0)
			(effects
				(font
					(size 1.27 1.27)
				)
				(hide yes)
			)
		)
		(property "MPN" ""
			(at 154.305 147.32 0)
			(effects
				(font
					(size 1.27 1.27)
					(thickness 0.15)
				)
				(justify left bottom)
				(hide yes)
			)
		)
		(property "Manufacturer" ""
			(at 154.305 142.24 0)
			(effects
				(font
					(size 1.27 1.27)
					(thickness 0.15)
				)
				(justify left bottom)
				(hide yes)
			)
		)
		(property "Author" "Antmicro"
			(at 154.94 144.78 0)
			(effects
				(font
					(size 1.27 1.27)
					(thickness 0.15)
				)
				(justify left bottom)
				(hide yes)
			)
		)
		(property "License" "Apache-2.0"
			(at 154.94 147.32 0)
			(effects
				(font
					(size 1.27 1.27)
					(thickness 0.15)
				)
				(justify left bottom)
				(hide yes)
			)
		)
		(pin "1"
		)
		(instances
			(project "jetson-agx-thor-baseboard"
				(path ""
					(reference "TP29")
					(unit 1)
				)
			)
		)
	)
	(symbol
		(lib_id "antmicroTestPoints:TP_0.75mm_SMD")
		(at 157.48 138.43 0)
		(mirror y)
		(unit 1)
		(exclude_from_sim no)
		(in_bom no)
		(on_board yes)
		(dnp no)
		(property "Reference" "TP30"
			(at 150.368 138.43 0)
			(effects
				(font
					(size 1.27 1.27)
					(thickness 0.15)
				)
				(justify left)
			)
		)
		(property "Value" "TP_0.75mm_SMD"
			(at 147.32 142.24 0)
			(effects
				(font
					(size 1.27 1.27)
					(thickness 0.15)
				)
				(justify left bottom)
				(hide yes)
			)
		)
		(property "Footprint" "antmicro-footprints:TP_SMD_0.75mm"
			(at 147.32 144.78 0)
			(effects
				(font
					(size 1.27 1.27)
					(thickness 0.15)
				)
				(justify left bottom)
				(hide yes)
			)
		)
		(property "Datasheet" ""
			(at 139.7 151.13 0)
			(effects
				(font
					(size 1.27 1.27)
					(thickness 0.15)
				)
				(justify left bottom)
				(hide yes)
			)
		)
		(property "Description" "SMT test point"
			(at 157.48 138.43 0)
			(effects
				(font
					(size 1.27 1.27)
				)
				(hide yes)
			)
		)
		(property "MPN" ""
			(at 146.685 149.86 0)
			(effects
				(font
					(size 1.27 1.27)
					(thickness 0.15)
				)
				(justify left bottom)
				(hide yes)
			)
		)
		(property "Manufacturer" ""
			(at 146.685 144.78 0)
			(effects
				(font
					(size 1.27 1.27)
					(thickness 0.15)
				)
				(justify left bottom)
				(hide yes)
			)
		)
		(property "Author" "Antmicro"
			(at 147.32 147.32 0)
			(effects
				(font
					(size 1.27 1.27)
					(thickness 0.15)
				)
				(justify left bottom)
				(hide yes)
			)
		)
		(property "License" "Apache-2.0"
			(at 147.32 149.86 0)
			(effects
				(font
					(size 1.27 1.27)
					(thickness 0.15)
				)
				(justify left bottom)
				(hide yes)
			)
		)
		(pin "1"
		)
		(instances
			(project "jetson-agx-thor-baseboard"
				(path ""
					(reference "TP30")
					(unit 1)
				)
			)
		)
	)
	(symbol
		(lib_id "antmicroCapacitors0402:C_100n_0402")
		(at 156.21 158.75 180)
		(unit 1)
		(exclude_from_sim no)
		(in_bom yes)
		(on_board yes)
		(dnp no)
		(property "Reference" "C61"
			(at 160.02 156.718 0)
			(effects
				(font
					(size 1.27 1.27)
				)
				(justify left bottom)
			)
		)
		(property "Value" "C_100n_0402"
			(at 135.89 148.59 0)
			(effects
				(font
					(size 1.27 1.27)
					(thickness 0.15)
				)
				(justify left bottom)
				(hide yes)
			)
		)
		(property "Footprint" "antmicro-footprints:C_0402_1005Metric"
			(at 135.89 146.05 0)
			(effects
				(font
					(size 1.27 1.27)
					(thickness 0.15)
				)
				(justify left bottom)
				(hide yes)
			)
		)
		(property "Datasheet" "https://www.murata.com/products/productdetail?partno=GRM155R61H104KE14%23"
			(at 135.89 143.51 0)
			(effects
				(font
					(size 1.27 1.27)
					(thickness 0.15)
				)
				(justify left bottom)
				(hide yes)
			)
		)
		(property "Description" "SMD Multilayer Ceramic Capacitor, 0.1 µF, 50 V, 0402 [1005 Metric], ± 10%, X5R, GRM Series"
			(at 156.21 158.75 0)
			(effects
				(font
					(size 1.27 1.27)
				)
				(hide yes)
			)
		)
		(property "Manufacturer" "Murata"
			(at 135.89 138.43 0)
			(effects
				(font
					(size 1.27 1.27)
					(thickness 0.15)
				)
				(justify left bottom)
				(hide yes)
			)
		)
		(property "MPN" "GRM155R61H104KE14D"
			(at 135.89 140.97 0)
			(effects
				(font
					(size 1.27 1.27)
					(thickness 0.15)
				)
				(justify left bottom)
				(hide yes)
			)
		)
		(property "Val" "100n"
			(at 152.4 159.385 0)
			(effects
				(font
					(size 1.27 1.27)
					(thickness 0.15)
				)
				(justify left bottom)
			)
		)
		(property "License" "Apache-2.0"
			(at 135.89 135.89 0)
			(effects
				(font
					(size 1.27 1.27)
					(thickness 0.15)
				)
				(justify left bottom)
				(hide yes)
			)
		)
		(property "Author" "Antmicro"
			(at 135.89 133.35 0)
			(effects
				(font
					(size 1.27 1.27)
					(thickness 0.15)
				)
				(justify left bottom)
				(hide yes)
			)
		)
		(property "Voltage" "50V"
			(at 135.89 130.81 0)
			(effects
				(font
					(size 1.27 1.27)
				)
				(justify left bottom)
				(hide yes)
			)
		)
		(property "Dielectric" "X5R"
			(at 135.89 128.27 0)
			(effects
				(font
					(size 1.27 1.27)
				)
				(justify left bottom)
				(hide yes)
			)
		)
		(property "Public" "False"
			(at 135.89 125.73 0)
			(effects
				(font
					(size 1.27 1.27)
				)
				(justify left bottom)
				(hide yes)
			)
		)
		(pin "1"
		)
		(pin "2"
		)
		(instances
			(project "jetson-agx-thor-baseboard"
				(path ""
					(reference "C61")
					(unit 1)
				)
			)
		)
	)
	(symbol
		(lib_id "antmicroResistors0402:R_200R_0402")
		(at 307.34 128.27 90)
		(unit 1)
		(exclude_from_sim no)
		(in_bom yes)
		(on_board yes)
		(dnp no)
		(fields_autoplaced yes)
		(property "Reference" "R205"
			(at 309.88 124.46 90)
			(effects
				(font
					(size 1.27 1.27)
				)
				(justify right)
			)
		)
		(property "Value" "R_200R_0402"
			(at 320.04 107.95 0)
			(effects
				(font
					(size 1.27 1.27)
					(thickness 0.15)
				)
				(justify left bottom)
				(hide yes)
			)
		)
		(property "Footprint" "antmicro-footprints:R_0402_1005Metric"
			(at 322.58 107.95 0)
			(effects
				(font
					(size 1.27 1.27)
					(thickness 0.15)
				)
				(justify left bottom)
				(hide yes)
			)
		)
		(property "Datasheet" "https://www.bourns.com/docs/product-datasheets/cr.pdf"
			(at 325.12 107.95 0)
			(effects
				(font
					(size 1.27 1.27)
					(thickness 0.15)
				)
				(justify left bottom)
				(hide yes)
			)
		)
		(property "Description" "SMD Chip Resistor, 200 ohm, ± 1%, 62.5 mW, 0402 [1005 Metric], Thick Film, General Purpose"
			(at 307.34 128.27 0)
			(effects
				(font
					(size 1.27 1.27)
				)
				(hide yes)
			)
		)
		(property "Manufacturer" "Bourns"
			(at 330.2 107.95 0)
			(effects
				(font
					(size 1.27 1.27)
					(thickness 0.15)
				)
				(justify left bottom)
				(hide yes)
			)
		)
		(property "MPN" "CR0402-FX-2000GLF"
			(at 327.66 107.95 0)
			(effects
				(font
					(size 1.27 1.27)
					(thickness 0.15)
				)
				(justify left bottom)
				(hide yes)
			)
		)
		(property "Val" "200R"
			(at 309.88 127 90)
			(effects
				(font
					(size 1.27 1.27)
					(thickness 0.15)
				)
				(justify right)
			)
		)
		(property "License" "Apache-2.0"
			(at 332.74 107.95 0)
			(effects
				(font
					(size 1.27 1.27)
					(thickness 0.15)
				)
				(justify left bottom)
				(hide yes)
			)
		)
		(property "Author" "Antmicro"
			(at 335.28 107.95 0)
			(effects
				(font
					(size 1.27 1.27)
					(thickness 0.15)
				)
				(justify left bottom)
				(hide yes)
			)
		)
		(property "Tolerance" "1%"
			(at 317.5 107.95 0)
			(effects
				(font
					(size 1.27 1.27)
				)
				(justify left bottom)
				(hide yes)
			)
		)
		(pin "1"
		)
		(pin "2"
		)
		(instances
			(project "jetson-agx-thor-baseboard"
				(path ""
					(reference "R205")
					(unit 1)
				)
			)
		)
	)
	(symbol
		(lib_id "antmicroResistors0402:R_330R_0402")
		(at 236.22 157.48 90)
		(unit 1)
		(exclude_from_sim no)
		(in_bom yes)
		(on_board yes)
		(dnp no)
		(property "Reference" "R200"
			(at 234.696 153.67 90)
			(effects
				(font
					(size 1.27 1.27)
					(thickness 0.15)
				)
				(justify left)
			)
		)
		(property "Value" "R_330R_0402"
			(at 248.92 137.16 0)
			(effects
				(font
					(size 1.27 1.27)
					(thickness 0.15)
				)
				(justify left bottom)
				(hide yes)
			)
		)
		(property "Footprint" "antmicro-footprints:R_0402_1005Metric"
			(at 251.46 137.16 0)
			(effects
				(font
					(size 1.27 1.27)
					(thickness 0.15)
				)
				(justify left bottom)
				(hide yes)
			)
		)
		(property "Datasheet" "https://www.bourns.com/docs/product-datasheets/cr.pdf"
			(at 254 137.16 0)
			(effects
				(font
					(size 1.27 1.27)
					(thickness 0.15)
				)
				(justify left bottom)
				(hide yes)
			)
		)
		(property "Description" "SMD Chip Resistor, 330 ohm, ± 1%, 62.5 mW, 0402 [1005 Metric], Thick Film, General Purpose"
			(at 236.22 157.48 0)
			(effects
				(font
					(size 1.27 1.27)
				)
				(hide yes)
			)
		)
		(property "MPN" "CR0402-FX-3300GLF"
			(at 256.54 137.16 0)
			(effects
				(font
					(size 1.27 1.27)
					(thickness 0.15)
				)
				(justify left bottom)
				(hide yes)
			)
		)
		(property "Manufacturer" "Bourns"
			(at 259.08 137.16 0)
			(effects
				(font
					(size 1.27 1.27)
					(thickness 0.15)
				)
				(justify left bottom)
				(hide yes)
			)
		)
		(property "License" "Apache-2.0"
			(at 261.62 137.16 0)
			(effects
				(font
					(size 1.27 1.27)
					(thickness 0.15)
				)
				(justify left bottom)
				(hide yes)
			)
		)
		(property "Author" "Antmicro"
			(at 264.16 137.16 0)
			(effects
				(font
					(size 1.27 1.27)
					(thickness 0.15)
				)
				(justify left bottom)
				(hide yes)
			)
		)
		(property "Val" "330R"
			(at 234.696 156.21 90)
			(effects
				(font
					(size 1.27 1.27)
					(thickness 0.15)
				)
				(justify left)
			)
		)
		(property "Tolerance" "1%"
			(at 246.38 137.16 0)
			(effects
				(font
					(size 1.27 1.27)
				)
				(justify left bottom)
				(hide yes)
			)
		)
		(pin "1"
		)
		(pin "2"
		)
		(instances
			(project ""
				(path ""
					(reference "R200")
					(unit 1)
				)
			)
		)
	)
	(symbol
		(lib_id "antmicroResistors0402:R_0R_0402")
		(at 138.43 133.35 0)
		(unit 1)
		(exclude_from_sim no)
		(in_bom yes)
		(on_board yes)
		(dnp no)
		(property "Reference" "R187"
			(at 136.144 132.08 0)
			(effects
				(font
					(size 1.27 1.27)
					(thickness 0.15)
				)
			)
		)
		(property "Value" "R_0R_0402"
			(at 158.75 146.05 0)
			(effects
				(font
					(size 1.27 1.27)
					(thickness 0.15)
				)
				(justify left bottom)
				(hide yes)
			)
		)
		(property "Footprint" "antmicro-footprints:R_0402_1005Metric"
			(at 158.75 148.59 0)
			(effects
				(font
					(size 1.27 1.27)
					(thickness 0.15)
				)
				(justify left bottom)
				(hide yes)
			)
		)
		(property "Datasheet" "https://industrial.panasonic.com/cdbs/www-data/pdf/RDA0000/AOA0000C301.pdf"
			(at 158.75 151.13 0)
			(effects
				(font
					(size 1.27 1.27)
					(thickness 0.15)
				)
				(justify left bottom)
				(hide yes)
			)
		)
		(property "Description" "SMD Chip Resistor, Jumper, 0 ohm, 100 mW, 0402 [1005 Metric], Thick Film, General Purpose"
			(at 138.43 133.35 0)
			(effects
				(font
					(size 1.27 1.27)
				)
				(hide yes)
			)
		)
		(property "MPN" "ERJ2GE0R00X"
			(at 158.75 153.67 0)
			(effects
				(font
					(size 1.27 1.27)
					(thickness 0.15)
				)
				(justify left bottom)
				(hide yes)
			)
		)
		(property "Manufacturer" "Panasonic"
			(at 158.75 156.21 0)
			(effects
				(font
					(size 1.27 1.27)
					(thickness 0.15)
				)
				(justify left bottom)
				(hide yes)
			)
		)
		(property "License" "Apache-2.0"
			(at 158.75 158.75 0)
			(effects
				(font
					(size 1.27 1.27)
					(thickness 0.15)
				)
				(justify left bottom)
				(hide yes)
			)
		)
		(property "Author" "Antmicro"
			(at 158.75 161.29 0)
			(effects
				(font
					(size 1.27 1.27)
					(thickness 0.15)
				)
				(justify left bottom)
				(hide yes)
			)
		)
		(property "Val" "0R"
			(at 144.526 132.08 0)
			(effects
				(font
					(size 1.27 1.27)
					(thickness 0.15)
				)
			)
		)
		(property "Tolerance" "~"
			(at 158.75 143.51 0)
			(effects
				(font
					(size 1.27 1.27)
				)
				(justify left bottom)
				(hide yes)
			)
		)
		(property "Current" "1A"
			(at 158.75 163.83 0)
			(effects
				(font
					(size 1.27 1.27)
					(thickness 0.15)
				)
				(justify left bottom)
				(hide yes)
			)
		)
		(pin "1"
		)
		(pin "2"
		)
		(instances
			(project "jetson-agx-thor-baseboard"
				(path ""
					(reference "R187")
					(unit 1)
				)
			)
		)
	)
	(symbol
		(lib_id "antmicropower:GND")
		(at 302.26 162.56 0)
		(mirror y)
		(unit 1)
		(exclude_from_sim no)
		(in_bom yes)
		(on_board yes)
		(dnp no)
		(property "Reference" "#PWR0359"
			(at 293.37 165.1 0)
			(effects
				(font
					(size 1.27 1.27)
					(thickness 0.15)
				)
				(justify left bottom)
				(hide yes)
			)
		)
		(property "Value" "GND"
			(at 302.26 166.37 0)
			(effects
				(font
					(size 1.27 1.27)
					(thickness 0.15)
				)
			)
		)
		(property "Footprint" ""
			(at 293.37 170.18 0)
			(effects
				(font
					(size 1.27 1.27)
					(thickness 0.15)
				)
				(justify left bottom)
				(hide yes)
			)
		)
		(property "Datasheet" ""
			(at 293.37 175.26 0)
			(effects
				(font
					(size 1.27 1.27)
					(thickness 0.15)
				)
				(justify left bottom)
				(hide yes)
			)
		)
		(property "Description" ""
			(at 302.26 162.56 0)
			(effects
				(font
					(size 1.27 1.27)
				)
				(hide yes)
			)
		)
		(property "Author" "Antmicro"
			(at 293.37 170.18 0)
			(effects
				(font
					(size 1.27 1.27)
					(thickness 0.15)
				)
				(justify left bottom)
				(hide yes)
			)
		)
		(property "License" "Apache-2.0"
			(at 293.37 172.72 0)
			(effects
				(font
					(size 1.27 1.27)
					(thickness 0.15)
				)
				(justify left bottom)
				(hide yes)
			)
		)
		(pin "1"
		)
		(instances
			(project "jetson-agx-thor-baseboard"
				(path ""
					(reference "#PWR0359")
					(unit 1)
				)
			)
		)
	)
	(symbol
		(lib_id "antmicroResistors0402:R_0R_0402")
		(at 138.43 128.27 0)
		(unit 1)
		(exclude_from_sim no)
		(in_bom yes)
		(on_board yes)
		(dnp no)
		(property "Reference" "R186"
			(at 136.144 127 0)
			(effects
				(font
					(size 1.27 1.27)
					(thickness 0.15)
				)
			)
		)
		(property "Value" "R_0R_0402"
			(at 158.75 140.97 0)
			(effects
				(font
					(size 1.27 1.27)
					(thickness 0.15)
				)
				(justify left bottom)
				(hide yes)
			)
		)
		(property "Footprint" "antmicro-footprints:R_0402_1005Metric"
			(at 158.75 143.51 0)
			(effects
				(font
					(size 1.27 1.27)
					(thickness 0.15)
				)
				(justify left bottom)
				(hide yes)
			)
		)
		(property "Datasheet" "https://industrial.panasonic.com/cdbs/www-data/pdf/RDA0000/AOA0000C301.pdf"
			(at 158.75 146.05 0)
			(effects
				(font
					(size 1.27 1.27)
					(thickness 0.15)
				)
				(justify left bottom)
				(hide yes)
			)
		)
		(property "Description" "SMD Chip Resistor, Jumper, 0 ohm, 100 mW, 0402 [1005 Metric], Thick Film, General Purpose"
			(at 138.43 128.27 0)
			(effects
				(font
					(size 1.27 1.27)
				)
				(hide yes)
			)
		)
		(property "MPN" "ERJ2GE0R00X"
			(at 158.75 148.59 0)
			(effects
				(font
					(size 1.27 1.27)
					(thickness 0.15)
				)
				(justify left bottom)
				(hide yes)
			)
		)
		(property "Manufacturer" "Panasonic"
			(at 158.75 151.13 0)
			(effects
				(font
					(size 1.27 1.27)
					(thickness 0.15)
				)
				(justify left bottom)
				(hide yes)
			)
		)
		(property "License" "Apache-2.0"
			(at 158.75 153.67 0)
			(effects
				(font
					(size 1.27 1.27)
					(thickness 0.15)
				)
				(justify left bottom)
				(hide yes)
			)
		)
		(property "Author" "Antmicro"
			(at 158.75 156.21 0)
			(effects
				(font
					(size 1.27 1.27)
					(thickness 0.15)
				)
				(justify left bottom)
				(hide yes)
			)
		)
		(property "Val" "0R"
			(at 144.526 127 0)
			(effects
				(font
					(size 1.27 1.27)
					(thickness 0.15)
				)
			)
		)
		(property "Tolerance" "~"
			(at 158.75 138.43 0)
			(effects
				(font
					(size 1.27 1.27)
				)
				(justify left bottom)
				(hide yes)
			)
		)
		(property "Current" "1A"
			(at 158.75 158.75 0)
			(effects
				(font
					(size 1.27 1.27)
					(thickness 0.15)
				)
				(justify left bottom)
				(hide yes)
			)
		)
		(pin "1"
		)
		(pin "2"
		)
		(instances
			(project "jetson-agx-thor-baseboard"
				(path ""
					(reference "R186")
					(unit 1)
				)
			)
		)
	)
	(symbol
		(lib_id "antmicroLEDIndicationDiscrete:LED_G_0603_LTST-C190GKT")
		(at 307.34 119.38 90)
		(unit 1)
		(exclude_from_sim no)
		(in_bom yes)
		(on_board yes)
		(dnp no)
		(fields_autoplaced yes)
		(property "Reference" "D14"
			(at 309.88 115.57 90)
			(effects
				(font
					(size 1.27 1.27)
					(thickness 0.15)
				)
				(justify right)
			)
		)
		(property "Value" "LED_G_0603_LTST-C190GKT"
			(at 314.96 96.52 0)
			(effects
				(font
					(size 1.27 1.27)
					(thickness 0.15)
				)
				(justify left bottom)
				(hide yes)
			)
		)
		(property "Footprint" "antmicro-footprints:LED_0603_1608Metric_G"
			(at 317.5 96.52 0)
			(effects
				(font
					(size 1.27 1.27)
					(thickness 0.15)
				)
				(justify left bottom)
				(hide yes)
			)
		)
		(property "Datasheet" "https://media.digikey.com/pdf/Data%20Sheets/Lite-On%20PDFs/LTST-C190GKT.pdf"
			(at 320.04 96.52 0)
			(effects
				(font
					(size 1.27 1.27)
					(thickness 0.15)
				)
				(justify left bottom)
				(hide yes)
			)
		)
		(property "Description" "LED, Green, SMD, 0603, 20 mA, 2.1 V, 569 nm"
			(at 307.34 119.38 0)
			(effects
				(font
					(size 1.27 1.27)
				)
				(hide yes)
			)
		)
		(property "MPN" "LTST-C190GKT"
			(at 322.58 96.52 0)
			(effects
				(font
					(size 1.27 1.27)
					(thickness 0.15)
				)
				(justify left bottom)
				(hide yes)
			)
		)
		(property "Manufacturer" "Lite-On"
			(at 325.12 96.52 0)
			(effects
				(font
					(size 1.27 1.27)
					(thickness 0.15)
				)
				(justify left bottom)
				(hide yes)
			)
		)
		(property "Color" "Green"
			(at 309.88 118.1099 90)
			(effects
				(font
					(size 1.27 1.27)
				)
				(justify right)
			)
		)
		(property "Author" "Antmicro"
			(at 327.66 96.52 0)
			(effects
				(font
					(size 1.27 1.27)
					(thickness 0.15)
				)
				(justify left bottom)
				(hide yes)
			)
		)
		(property "License" "Apache-2.0"
			(at 330.2 96.52 0)
			(effects
				(font
					(size 1.27 1.27)
					(thickness 0.15)
				)
				(justify left bottom)
				(hide yes)
			)
		)
		(pin "2"
		)
		(pin "1"
		)
		(instances
			(project ""
				(path ""
					(reference "D14")
					(unit 1)
				)
			)
		)
	)
	(symbol
		(lib_id "antmicroLEDIndicationDiscrete:LED_Y_0603_LTST-C191KSKT")
		(at 285.75 119.38 90)
		(unit 1)
		(exclude_from_sim no)
		(in_bom yes)
		(on_board yes)
		(dnp no)
		(fields_autoplaced yes)
		(property "Reference" "D30"
			(at 288.29 115.57 90)
			(effects
				(font
					(size 1.27 1.27)
					(thickness 0.15)
				)
				(justify right)
			)
		)
		(property "Value" "LED_Y_0603_LTST-C191KSKT"
			(at 293.37 96.52 0)
			(effects
				(font
					(size 1.27 1.27)
					(thickness 0.15)
				)
				(justify left bottom)
				(hide yes)
			)
		)
		(property "Footprint" "antmicro-footprints:LED_0603_1608Metric_Y"
			(at 295.91 96.52 0)
			(effects
				(font
					(size 1.27 1.27)
					(thickness 0.15)
				)
				(justify left bottom)
				(hide yes)
			)
		)
		(property "Datasheet" "https://optoelectronics.liteon.com/upload/download/DS22-2000-224/LTST-C191KSKT.PDF"
			(at 298.45 96.52 0)
			(effects
				(font
					(size 1.27 1.27)
					(thickness 0.15)
				)
				(justify left bottom)
				(hide yes)
			)
		)
		(property "Description" "LED, Yellow, SMD, 0603, 30 mA, 2.1 V, 588 nm"
			(at 285.75 119.38 0)
			(effects
				(font
					(size 1.27 1.27)
				)
				(hide yes)
			)
		)
		(property "MPN" "LTST-C191KSKT"
			(at 300.99 96.52 0)
			(effects
				(font
					(size 1.27 1.27)
					(thickness 0.15)
				)
				(justify left bottom)
				(hide yes)
			)
		)
		(property "Manufacturer" "Lite-On"
			(at 303.53 96.52 0)
			(effects
				(font
					(size 1.27 1.27)
					(thickness 0.15)
				)
				(justify left bottom)
				(hide yes)
			)
		)
		(property "Color" "Yellow"
			(at 288.29 118.11 90)
			(effects
				(font
					(size 1.27 1.27)
				)
				(justify right)
			)
		)
		(property "Author" "Antmicro"
			(at 306.07 96.52 0)
			(effects
				(font
					(size 1.27 1.27)
					(thickness 0.15)
				)
				(justify left bottom)
				(hide yes)
			)
		)
		(property "License" "Apache-2.0"
			(at 308.61 96.52 0)
			(effects
				(font
					(size 1.27 1.27)
					(thickness 0.15)
				)
				(justify left bottom)
				(hide yes)
			)
		)
		(pin "1"
		)
		(pin "2"
		)
		(instances
			(project "jetson-agx-thor-baseboard"
				(path ""
					(reference "D30")
					(unit 1)
				)
			)
		)
	)
	(symbol
		(lib_id "antmicroWire2BoardConnectors:Amphenol_SFP28_Cage_U773GC16382071")
		(at 226.06 147.32 0)
		(unit 1)
		(exclude_from_sim no)
		(in_bom yes)
		(on_board yes)
		(dnp no)
		(fields_autoplaced yes)
		(property "Reference" "J19"
			(at 217.17 138.43 0)
			(effects
				(font
					(size 1.27 1.27)
					(thickness 0.15)
				)
			)
		)
		(property "Value" "Amphenol_SFP28_Cage_U773GC16382071"
			(at 241.3 154.94 0)
			(effects
				(font
					(size 1.27 1.27)
					(thickness 0.15)
				)
				(justify left bottom)
				(hide yes)
			)
		)
		(property "Footprint" "antmicro-footprints:Conn_Amphenol_SFP28_Cage_U773GC16382071"
			(at 241.3 157.48 0)
			(effects
				(font
					(size 1.27 1.27)
					(thickness 0.15)
				)
				(justify left bottom)
				(hide yes)
			)
		)
		(property "Datasheet" "https://cdn.amphenol-cs.com/media/wysiwyg/files/documentation/datasheet/inputoutput/hsio_cn_ultraport_sfp.pdf"
			(at 241.3 160.02 0)
			(effects
				(font
					(size 1.27 1.27)
					(thickness 0.15)
				)
				(justify left bottom)
				(hide yes)
			)
		)
		(property "Description" "SFP28 Receptacle Cage"
			(at 241.3 162.56 0)
			(effects
				(font
					(size 1.27 1.27)
					(thickness 0.15)
				)
				(justify left bottom)
				(hide yes)
			)
		)
		(property "MPN" "U773GC16382071"
			(at 217.17 140.97 0)
			(effects
				(font
					(size 1.27 1.27)
					(thickness 0.15)
				)
			)
		)
		(property "Manufacturer" "Amphenol"
			(at 241.3 165.1 0)
			(effects
				(font
					(size 1.27 1.27)
					(thickness 0.15)
				)
				(justify left bottom)
				(hide yes)
			)
		)
		(property "Author" "Antmicro"
			(at 241.3 167.64 0)
			(effects
				(font
					(size 1.27 1.27)
					(thickness 0.15)
				)
				(justify left bottom)
				(hide yes)
			)
		)
		(property "License" "Apache-2.0"
			(at 241.3 170.18 0)
			(effects
				(font
					(size 1.27 1.27)
					(thickness 0.15)
				)
				(justify left bottom)
				(hide yes)
			)
		)
		(pin "SH"
		)
		(instances
			(project ""
				(path ""
					(reference "J19")
					(unit 1)
				)
			)
		)
	)
	(symbol
		(lib_id "antmicroCapacitors0402:C_100n_0402")
		(at 302.26 157.48 90)
		(unit 1)
		(exclude_from_sim no)
		(in_bom yes)
		(on_board yes)
		(dnp no)
		(fields_autoplaced yes)
		(property "Reference" "C178"
			(at 304.8 153.6636 90)
			(effects
				(font
					(size 1.27 1.27)
					(thickness 0.15)
				)
				(justify right)
			)
		)
		(property "Value" "C_100n_0402"
			(at 312.42 137.16 0)
			(effects
				(font
					(size 1.27 1.27)
					(thickness 0.15)
				)
				(justify left bottom)
				(hide yes)
			)
		)
		(property "Footprint" "antmicro-footprints:C_0402_1005Metric"
			(at 314.96 137.16 0)
			(effects
				(font
					(size 1.27 1.27)
					(thickness 0.15)
				)
				(justify left bottom)
				(hide yes)
			)
		)
		(property "Datasheet" "https://www.murata.com/products/productdetail?partno=GRM155R61H104KE14%23"
			(at 317.5 137.16 0)
			(effects
				(font
					(size 1.27 1.27)
					(thickness 0.15)
				)
				(justify left bottom)
				(hide yes)
			)
		)
		(property "Description" "SMD Multilayer Ceramic Capacitor, 0.1 µF, 50 V, 0402 [1005 Metric], ± 10%, X5R, GRM Series"
			(at 302.26 157.48 0)
			(effects
				(font
					(size 1.27 1.27)
				)
				(hide yes)
			)
		)
		(property "MPN" "GRM155R61H104KE14D"
			(at 320.04 137.16 0)
			(effects
				(font
					(size 1.27 1.27)
					(thickness 0.15)
				)
				(justify left bottom)
				(hide yes)
			)
		)
		(property "Manufacturer" "Murata"
			(at 322.58 137.16 0)
			(effects
				(font
					(size 1.27 1.27)
					(thickness 0.15)
				)
				(justify left bottom)
				(hide yes)
			)
		)
		(property "License" "Apache-2.0"
			(at 325.12 137.16 0)
			(effects
				(font
					(size 1.27 1.27)
					(thickness 0.15)
				)
				(justify left bottom)
				(hide yes)
			)
		)
		(property "Author" "Antmicro"
			(at 327.66 137.16 0)
			(effects
				(font
					(size 1.27 1.27)
					(thickness 0.15)
				)
				(justify left bottom)
				(hide yes)
			)
		)
		(property "Val" "100n"
			(at 304.8 156.2036 90)
			(effects
				(font
					(size 1.27 1.27)
					(thickness 0.15)
				)
				(justify right)
			)
		)
		(property "Voltage" "50V"
			(at 330.2 137.16 0)
			(effects
				(font
					(size 1.27 1.27)
				)
				(justify left bottom)
				(hide yes)
			)
		)
		(property "Dielectric" "X5R"
			(at 332.74 137.16 0)
			(effects
				(font
					(size 1.27 1.27)
				)
				(justify left bottom)
				(hide yes)
			)
		)
		(pin "2"
		)
		(pin "1"
		)
		(instances
			(project "jetson-agx-thor-baseboard"
				(path ""
					(reference "C178")
					(unit 1)
				)
			)
		)
	)
	(symbol
		(lib_id "antmicroCapacitors0402:C_100n_0402")
		(at 160.02 161.29 180)
		(unit 1)
		(exclude_from_sim no)
		(in_bom yes)
		(on_board yes)
		(dnp no)
		(property "Reference" "C65"
			(at 163.83 159.258 0)
			(effects
				(font
					(size 1.27 1.27)
				)
				(justify left bottom)
			)
		)
		(property "Value" "C_100n_0402"
			(at 139.7 151.13 0)
			(effects
				(font
					(size 1.27 1.27)
					(thickness 0.15)
				)
				(justify left bottom)
				(hide yes)
			)
		)
		(property "Footprint" "antmicro-footprints:C_0402_1005Metric"
			(at 139.7 148.59 0)
			(effects
				(font
					(size 1.27 1.27)
					(thickness 0.15)
				)
				(justify left bottom)
				(hide yes)
			)
		)
		(property "Datasheet" "https://www.murata.com/products/productdetail?partno=GRM155R61H104KE14%23"
			(at 139.7 146.05 0)
			(effects
				(font
					(size 1.27 1.27)
					(thickness 0.15)
				)
				(justify left bottom)
				(hide yes)
			)
		)
		(property "Description" "SMD Multilayer Ceramic Capacitor, 0.1 µF, 50 V, 0402 [1005 Metric], ± 10%, X5R, GRM Series"
			(at 160.02 161.29 0)
			(effects
				(font
					(size 1.27 1.27)
				)
				(hide yes)
			)
		)
		(property "Manufacturer" "Murata"
			(at 139.7 140.97 0)
			(effects
				(font
					(size 1.27 1.27)
					(thickness 0.15)
				)
				(justify left bottom)
				(hide yes)
			)
		)
		(property "MPN" "GRM155R61H104KE14D"
			(at 139.7 143.51 0)
			(effects
				(font
					(size 1.27 1.27)
					(thickness 0.15)
				)
				(justify left bottom)
				(hide yes)
			)
		)
		(property "Val" "100n"
			(at 156.21 161.925 0)
			(effects
				(font
					(size 1.27 1.27)
					(thickness 0.15)
				)
				(justify left bottom)
			)
		)
		(property "License" "Apache-2.0"
			(at 139.7 138.43 0)
			(effects
				(font
					(size 1.27 1.27)
					(thickness 0.15)
				)
				(justify left bottom)
				(hide yes)
			)
		)
		(property "Author" "Antmicro"
			(at 139.7 135.89 0)
			(effects
				(font
					(size 1.27 1.27)
					(thickness 0.15)
				)
				(justify left bottom)
				(hide yes)
			)
		)
		(property "Voltage" "50V"
			(at 139.7 133.35 0)
			(effects
				(font
					(size 1.27 1.27)
				)
				(justify left bottom)
				(hide yes)
			)
		)
		(property "Dielectric" "X5R"
			(at 139.7 130.81 0)
			(effects
				(font
					(size 1.27 1.27)
				)
				(justify left bottom)
				(hide yes)
			)
		)
		(property "Public" "False"
			(at 139.7 128.27 0)
			(effects
				(font
					(size 1.27 1.27)
				)
				(justify left bottom)
				(hide yes)
			)
		)
		(pin "1"
		)
		(pin "2"
		)
		(instances
			(project "jetson-agx-thor-baseboard"
				(path ""
					(reference "C65")
					(unit 1)
				)
			)
		)
	)
	(symbol
		(lib_id "antmicropower:+3V3")
		(at 285.75 113.03 0)
		(unit 1)
		(exclude_from_sim no)
		(in_bom yes)
		(on_board yes)
		(dnp no)
		(property "Reference" "#PWR0353"
			(at 285.75 116.84 0)
			(effects
				(font
					(size 1.27 1.27)
				)
				(justify left bottom)
				(hide yes)
			)
		)
		(property "Value" "+3V3"
			(at 283.21 109.22 0)
			(effects
				(font
					(size 1.27 1.27)
				)
				(justify left)
			)
		)
		(property "Footprint" ""
			(at 285.75 113.03 0)
			(effects
				(font
					(size 1.27 1.27)
				)
				(justify left bottom)
				(hide yes)
			)
		)
		(property "Datasheet" ""
			(at 285.75 113.03 0)
			(effects
				(font
					(size 1.27 1.27)
				)
				(justify left bottom)
				(hide yes)
			)
		)
		(property "Description" ""
			(at 285.75 113.03 0)
			(effects
				(font
					(size 1.27 1.27)
				)
				(hide yes)
			)
		)
		(property "Author" "Antmicro"
			(at 300.99 115.57 0)
			(effects
				(font
					(size 1.27 1.27)
					(thickness 0.15)
				)
				(justify left bottom)
				(hide yes)
			)
		)
		(property "License" "Apache-2.0"
			(at 300.99 118.11 0)
			(effects
				(font
					(size 1.27 1.27)
					(thickness 0.15)
				)
				(justify left bottom)
				(hide yes)
			)
		)
		(pin "1"
		)
		(instances
			(project "jetson-agx-thor-baseboard"
				(path ""
					(reference "#PWR0353")
					(unit 1)
				)
			)
		)
	)
	(symbol
		(lib_id "antmicroCapacitors0402:C_100n_0402")
		(at 156.21 151.13 180)
		(unit 1)
		(exclude_from_sim no)
		(in_bom yes)
		(on_board yes)
		(dnp no)
		(property "Reference" "C57"
			(at 160.02 149.098 0)
			(effects
				(font
					(size 1.27 1.27)
				)
				(justify left bottom)
			)
		)
		(property "Value" "C_100n_0402"
			(at 135.89 140.97 0)
			(effects
				(font
					(size 1.27 1.27)
					(thickness 0.15)
				)
				(justify left bottom)
				(hide yes)
			)
		)
		(property "Footprint" "antmicro-footprints:C_0402_1005Metric"
			(at 135.89 138.43 0)
			(effects
				(font
					(size 1.27 1.27)
					(thickness 0.15)
				)
				(justify left bottom)
				(hide yes)
			)
		)
		(property "Datasheet" "https://www.murata.com/products/productdetail?partno=GRM155R61H104KE14%23"
			(at 135.89 135.89 0)
			(effects
				(font
					(size 1.27 1.27)
					(thickness 0.15)
				)
				(justify left bottom)
				(hide yes)
			)
		)
		(property "Description" "SMD Multilayer Ceramic Capacitor, 0.1 µF, 50 V, 0402 [1005 Metric], ± 10%, X5R, GRM Series"
			(at 156.21 151.13 0)
			(effects
				(font
					(size 1.27 1.27)
				)
				(hide yes)
			)
		)
		(property "Manufacturer" "Murata"
			(at 135.89 130.81 0)
			(effects
				(font
					(size 1.27 1.27)
					(thickness 0.15)
				)
				(justify left bottom)
				(hide yes)
			)
		)
		(property "MPN" "GRM155R61H104KE14D"
			(at 135.89 133.35 0)
			(effects
				(font
					(size 1.27 1.27)
					(thickness 0.15)
				)
				(justify left bottom)
				(hide yes)
			)
		)
		(property "Val" "100n"
			(at 152.4 151.765 0)
			(effects
				(font
					(size 1.27 1.27)
					(thickness 0.15)
				)
				(justify left bottom)
			)
		)
		(property "License" "Apache-2.0"
			(at 135.89 128.27 0)
			(effects
				(font
					(size 1.27 1.27)
					(thickness 0.15)
				)
				(justify left bottom)
				(hide yes)
			)
		)
		(property "Author" "Antmicro"
			(at 135.89 125.73 0)
			(effects
				(font
					(size 1.27 1.27)
					(thickness 0.15)
				)
				(justify left bottom)
				(hide yes)
			)
		)
		(property "Voltage" "50V"
			(at 135.89 123.19 0)
			(effects
				(font
					(size 1.27 1.27)
				)
				(justify left bottom)
				(hide yes)
			)
		)
		(property "Dielectric" "X5R"
			(at 135.89 120.65 0)
			(effects
				(font
					(size 1.27 1.27)
				)
				(justify left bottom)
				(hide yes)
			)
		)
		(property "Public" "False"
			(at 135.89 118.11 0)
			(effects
				(font
					(size 1.27 1.27)
				)
				(justify left bottom)
				(hide yes)
			)
		)
		(pin "1"
		)
		(pin "2"
		)
		(instances
			(project "jetson-agx-thor-baseboard"
				(path ""
					(reference "C57")
					(unit 1)
				)
			)
		)
	)
	(symbol
		(lib_id "antmicroResistors0402:R_1k_0402")
		(at 151.13 120.65 90)
		(unit 1)
		(exclude_from_sim no)
		(in_bom yes)
		(on_board yes)
		(dnp no)
		(property "Reference" "R188"
			(at 152.4 116.84 90)
			(effects
				(font
					(size 1.27 1.27)
					(thickness 0.15)
				)
				(justify right)
			)
		)
		(property "Value" "R_1k_0402"
			(at 163.83 100.33 0)
			(effects
				(font
					(size 1.27 1.27)
					(thickness 0.15)
				)
				(justify left bottom)
				(hide yes)
			)
		)
		(property "Footprint" "antmicro-footprints:R_0402_1005Metric"
			(at 166.37 100.33 0)
			(effects
				(font
					(size 1.27 1.27)
					(thickness 0.15)
				)
				(justify left bottom)
				(hide yes)
			)
		)
		(property "Datasheet" "https://www.bourns.com/docs/product-datasheets/cr.pdf"
			(at 168.91 100.33 0)
			(effects
				(font
					(size 1.27 1.27)
					(thickness 0.15)
				)
				(justify left bottom)
				(hide yes)
			)
		)
		(property "Description" "SMD Chip Resistor, 1 kohm, ± 1%, 63 mW, 0402 [1005 Metric], Thick Film, General Purpose"
			(at 151.13 120.65 0)
			(effects
				(font
					(size 1.27 1.27)
				)
				(hide yes)
			)
		)
		(property "MPN" "CR0402-FX-1001GLF"
			(at 171.45 100.33 0)
			(effects
				(font
					(size 1.27 1.27)
					(thickness 0.15)
				)
				(justify left bottom)
				(hide yes)
			)
		)
		(property "Manufacturer" "Bourns"
			(at 173.99 100.33 0)
			(effects
				(font
					(size 1.27 1.27)
					(thickness 0.15)
				)
				(justify left bottom)
				(hide yes)
			)
		)
		(property "License" "Apache-2.0"
			(at 176.53 100.33 0)
			(effects
				(font
					(size 1.27 1.27)
					(thickness 0.15)
				)
				(justify left bottom)
				(hide yes)
			)
		)
		(property "Author" "Antmicro"
			(at 179.07 100.33 0)
			(effects
				(font
					(size 1.27 1.27)
					(thickness 0.15)
				)
				(justify left bottom)
				(hide yes)
			)
		)
		(property "Val" "1k"
			(at 152.4 119.38 90)
			(effects
				(font
					(size 1.27 1.27)
					(thickness 0.15)
				)
				(justify right)
			)
		)
		(property "Tolerance" "1%"
			(at 161.29 100.33 0)
			(effects
				(font
					(size 1.27 1.27)
				)
				(justify left bottom)
				(hide yes)
			)
		)
		(pin "2"
		)
		(pin "1"
		)
		(instances
			(project "jetson-agx-thor-baseboard"
				(path ""
					(reference "R188")
					(unit 1)
				)
			)
		)
	)
	(symbol
		(lib_id "antmicropower:GND")
		(at 240.03 162.56 0)
		(mirror y)
		(unit 1)
		(exclude_from_sim no)
		(in_bom yes)
		(on_board yes)
		(dnp no)
		(property "Reference" "#PWR0350"
			(at 231.14 165.1 0)
			(effects
				(font
					(size 1.27 1.27)
					(thickness 0.15)
				)
				(justify left bottom)
				(hide yes)
			)
		)
		(property "Value" "GND"
			(at 240.03 166.37 0)
			(effects
				(font
					(size 1.27 1.27)
					(thickness 0.15)
				)
			)
		)
		(property "Footprint" ""
			(at 231.14 170.18 0)
			(effects
				(font
					(size 1.27 1.27)
					(thickness 0.15)
				)
				(justify left bottom)
				(hide yes)
			)
		)
		(property "Datasheet" ""
			(at 231.14 175.26 0)
			(effects
				(font
					(size 1.27 1.27)
					(thickness 0.15)
				)
				(justify left bottom)
				(hide yes)
			)
		)
		(property "Description" ""
			(at 240.03 162.56 0)
			(effects
				(font
					(size 1.27 1.27)
				)
				(hide yes)
			)
		)
		(property "Author" "Antmicro"
			(at 231.14 170.18 0)
			(effects
				(font
					(size 1.27 1.27)
					(thickness 0.15)
				)
				(justify left bottom)
				(hide yes)
			)
		)
		(property "License" "Apache-2.0"
			(at 231.14 172.72 0)
			(effects
				(font
					(size 1.27 1.27)
					(thickness 0.15)
				)
				(justify left bottom)
				(hide yes)
			)
		)
		(pin "1"
		)
		(instances
			(project "jetson-agx-thor-baseboard"
				(path ""
					(reference "#PWR0350")
					(unit 1)
				)
			)
		)
	)
	(symbol
		(lib_id "antmicroResistors0402:R_1k_0402")
		(at 166.37 120.65 90)
		(unit 1)
		(exclude_from_sim no)
		(in_bom yes)
		(on_board yes)
		(dnp no)
		(property "Reference" "R192"
			(at 167.64 116.84 90)
			(effects
				(font
					(size 1.27 1.27)
					(thickness 0.15)
				)
				(justify right)
			)
		)
		(property "Value" "R_1k_0402"
			(at 179.07 100.33 0)
			(effects
				(font
					(size 1.27 1.27)
					(thickness 0.15)
				)
				(justify left bottom)
				(hide yes)
			)
		)
		(property "Footprint" "antmicro-footprints:R_0402_1005Metric"
			(at 181.61 100.33 0)
			(effects
				(font
					(size 1.27 1.27)
					(thickness 0.15)
				)
				(justify left bottom)
				(hide yes)
			)
		)
		(property "Datasheet" "https://www.bourns.com/docs/product-datasheets/cr.pdf"
			(at 184.15 100.33 0)
			(effects
				(font
					(size 1.27 1.27)
					(thickness 0.15)
				)
				(justify left bottom)
				(hide yes)
			)
		)
		(property "Description" "SMD Chip Resistor, 1 kohm, ± 1%, 63 mW, 0402 [1005 Metric], Thick Film, General Purpose"
			(at 166.37 120.65 0)
			(effects
				(font
					(size 1.27 1.27)
				)
				(hide yes)
			)
		)
		(property "MPN" "CR0402-FX-1001GLF"
			(at 186.69 100.33 0)
			(effects
				(font
					(size 1.27 1.27)
					(thickness 0.15)
				)
				(justify left bottom)
				(hide yes)
			)
		)
		(property "Manufacturer" "Bourns"
			(at 189.23 100.33 0)
			(effects
				(font
					(size 1.27 1.27)
					(thickness 0.15)
				)
				(justify left bottom)
				(hide yes)
			)
		)
		(property "License" "Apache-2.0"
			(at 191.77 100.33 0)
			(effects
				(font
					(size 1.27 1.27)
					(thickness 0.15)
				)
				(justify left bottom)
				(hide yes)
			)
		)
		(property "Author" "Antmicro"
			(at 194.31 100.33 0)
			(effects
				(font
					(size 1.27 1.27)
					(thickness 0.15)
				)
				(justify left bottom)
				(hide yes)
			)
		)
		(property "Val" "1k"
			(at 167.64 119.38 90)
			(effects
				(font
					(size 1.27 1.27)
					(thickness 0.15)
				)
				(justify right)
			)
		)
		(property "Tolerance" "1%"
			(at 176.53 100.33 0)
			(effects
				(font
					(size 1.27 1.27)
				)
				(justify left bottom)
				(hide yes)
			)
		)
		(pin "2"
		)
		(pin "1"
		)
		(instances
			(project "jetson-agx-thor-baseboard"
				(path ""
					(reference "R192")
					(unit 1)
				)
			)
		)
	)
	(symbol
		(lib_id "antmicropower:+3V3")
		(at 307.34 113.03 0)
		(unit 1)
		(exclude_from_sim no)
		(in_bom yes)
		(on_board yes)
		(dnp no)
		(property "Reference" "#PWR0356"
			(at 307.34 116.84 0)
			(effects
				(font
					(size 1.27 1.27)
				)
				(justify left bottom)
				(hide yes)
			)
		)
		(property "Value" "+3V3"
			(at 304.8 109.22 0)
			(effects
				(font
					(size 1.27 1.27)
				)
				(justify left)
			)
		)
		(property "Footprint" ""
			(at 307.34 113.03 0)
			(effects
				(font
					(size 1.27 1.27)
				)
				(justify left bottom)
				(hide yes)
			)
		)
		(property "Datasheet" ""
			(at 307.34 113.03 0)
			(effects
				(font
					(size 1.27 1.27)
				)
				(justify left bottom)
				(hide yes)
			)
		)
		(property "Description" ""
			(at 307.34 113.03 0)
			(effects
				(font
					(size 1.27 1.27)
				)
				(hide yes)
			)
		)
		(property "Author" "Antmicro"
			(at 322.58 115.57 0)
			(effects
				(font
					(size 1.27 1.27)
					(thickness 0.15)
				)
				(justify left bottom)
				(hide yes)
			)
		)
		(property "License" "Apache-2.0"
			(at 322.58 118.11 0)
			(effects
				(font
					(size 1.27 1.27)
					(thickness 0.15)
				)
				(justify left bottom)
				(hide yes)
			)
		)
		(pin "1"
		)
		(instances
			(project "jetson-agx-thor-baseboard"
				(path ""
					(reference "#PWR0356")
					(unit 1)
				)
			)
		)
	)
	(symbol
		(lib_id "antmicroWire2BoardConnectors:Amphenol_SFP28_1x20_UE763GA202600T")
		(at 185.42 118.11 0)
		(unit 1)
		(exclude_from_sim no)
		(in_bom yes)
		(on_board yes)
		(dnp no)
		(fields_autoplaced yes)
		(property "Reference" "J12"
			(at 198.12 110.49 0)
			(effects
				(font
					(size 1.27 1.27)
					(thickness 0.15)
				)
			)
		)
		(property "Value" "Amphenol_SFP28_1x20_UE763GA202600T"
			(at 223.52 125.73 0)
			(effects
				(font
					(size 1.27 1.27)
					(thickness 0.15)
				)
				(justify left bottom)
				(hide yes)
			)
		)
		(property "Footprint" "antmicro-footprints:Conn_Amphenol_SFP28_1x20_UE763GA202600T"
			(at 223.52 128.27 0)
			(effects
				(font
					(size 1.27 1.27)
					(thickness 0.15)
				)
				(justify left bottom)
				(hide yes)
			)
		)
		(property "Datasheet" "https://cdn.amphenol-cs.com/media/wysiwyg/files/documentation/datasheet/inputoutput/hsio_cn_ultraport_sfp.pdf"
			(at 223.52 130.81 0)
			(effects
				(font
					(size 1.27 1.27)
					(thickness 0.15)
				)
				(justify left bottom)
				(hide yes)
			)
		)
		(property "Description" "20 Position SFP28 Receptacle with no Cage, Right Angle"
			(at 223.52 133.35 0)
			(effects
				(font
					(size 1.27 1.27)
					(thickness 0.15)
				)
				(justify left bottom)
				(hide yes)
			)
		)
		(property "MPN" "UE763GA202600T"
			(at 198.12 113.03 0)
			(effects
				(font
					(size 1.27 1.27)
					(thickness 0.15)
				)
			)
		)
		(property "Manufacturer" "Amphenol"
			(at 223.52 135.89 0)
			(effects
				(font
					(size 1.27 1.27)
					(thickness 0.15)
				)
				(justify left bottom)
				(hide yes)
			)
		)
		(property "Author" "Antmicro"
			(at 223.52 138.43 0)
			(effects
				(font
					(size 1.27 1.27)
					(thickness 0.15)
				)
				(justify left bottom)
				(hide yes)
			)
		)
		(property "License" "Apache-2.0"
			(at 223.52 140.97 0)
			(effects
				(font
					(size 1.27 1.27)
					(thickness 0.15)
				)
				(justify left bottom)
				(hide yes)
			)
		)
		(pin "3"
		)
		(pin "7"
		)
		(pin "12"
		)
		(pin "2"
		)
		(pin "13"
		)
		(pin "1"
		)
		(pin "20"
		)
		(pin "11"
		)
		(pin "15"
		)
		(pin "16"
		)
		(pin "4"
		)
		(pin "6"
		)
		(pin "17"
		)
		(pin "14"
		)
		(pin "10"
		)
		(pin "5"
		)
		(pin "9"
		)
		(pin "19"
		)
		(pin "8"
		)
		(pin "18"
		)
		(instances
			(project ""
				(path ""
					(reference "J12")
					(unit 1)
				)
			)
		)
	)
	(symbol
		(lib_id "antmicropower:GND")
		(at 311.15 162.56 0)
		(mirror y)
		(unit 1)
		(exclude_from_sim no)
		(in_bom yes)
		(on_board yes)
		(dnp no)
		(property "Reference" "#PWR0360"
			(at 302.26 165.1 0)
			(effects
				(font
					(size 1.27 1.27)
					(thickness 0.15)
				)
				(justify left bottom)
				(hide yes)
			)
		)
		(property "Value" "GND"
			(at 311.15 166.37 0)
			(effects
				(font
					(size 1.27 1.27)
					(thickness 0.15)
				)
			)
		)
		(property "Footprint" ""
			(at 302.26 170.18 0)
			(effects
				(font
					(size 1.27 1.27)
					(thickness 0.15)
				)
				(justify left bottom)
				(hide yes)
			)
		)
		(property "Datasheet" ""
			(at 302.26 175.26 0)
			(effects
				(font
					(size 1.27 1.27)
					(thickness 0.15)
				)
				(justify left bottom)
				(hide yes)
			)
		)
		(property "Description" ""
			(at 311.15 162.56 0)
			(effects
				(font
					(size 1.27 1.27)
				)
				(hide yes)
			)
		)
		(property "Author" "Antmicro"
			(at 302.26 170.18 0)
			(effects
				(font
					(size 1.27 1.27)
					(thickness 0.15)
				)
				(justify left bottom)
				(hide yes)
			)
		)
		(property "License" "Apache-2.0"
			(at 302.26 172.72 0)
			(effects
				(font
					(size 1.27 1.27)
					(thickness 0.15)
				)
				(justify left bottom)
				(hide yes)
			)
		)
		(pin "1"
		)
		(instances
			(project "jetson-agx-thor-baseboard"
				(path ""
					(reference "#PWR0360")
					(unit 1)
				)
			)
		)
	)
	(symbol
		(lib_id "antmicroCapacitors0402:C_100n_0402")
		(at 160.02 153.67 180)
		(unit 1)
		(exclude_from_sim no)
		(in_bom yes)
		(on_board yes)
		(dnp no)
		(property "Reference" "C58"
			(at 163.83 151.638 0)
			(effects
				(font
					(size 1.27 1.27)
				)
				(justify left bottom)
			)
		)
		(property "Value" "C_100n_0402"
			(at 139.7 143.51 0)
			(effects
				(font
					(size 1.27 1.27)
					(thickness 0.15)
				)
				(justify left bottom)
				(hide yes)
			)
		)
		(property "Footprint" "antmicro-footprints:C_0402_1005Metric"
			(at 139.7 140.97 0)
			(effects
				(font
					(size 1.27 1.27)
					(thickness 0.15)
				)
				(justify left bottom)
				(hide yes)
			)
		)
		(property "Datasheet" "https://www.murata.com/products/productdetail?partno=GRM155R61H104KE14%23"
			(at 139.7 138.43 0)
			(effects
				(font
					(size 1.27 1.27)
					(thickness 0.15)
				)
				(justify left bottom)
				(hide yes)
			)
		)
		(property "Description" "SMD Multilayer Ceramic Capacitor, 0.1 µF, 50 V, 0402 [1005 Metric], ± 10%, X5R, GRM Series"
			(at 160.02 153.67 0)
			(effects
				(font
					(size 1.27 1.27)
				)
				(hide yes)
			)
		)
		(property "Manufacturer" "Murata"
			(at 139.7 133.35 0)
			(effects
				(font
					(size 1.27 1.27)
					(thickness 0.15)
				)
				(justify left bottom)
				(hide yes)
			)
		)
		(property "MPN" "GRM155R61H104KE14D"
			(at 139.7 135.89 0)
			(effects
				(font
					(size 1.27 1.27)
					(thickness 0.15)
				)
				(justify left bottom)
				(hide yes)
			)
		)
		(property "Val" "100n"
			(at 156.21 154.305 0)
			(effects
				(font
					(size 1.27 1.27)
					(thickness 0.15)
				)
				(justify left bottom)
			)
		)
		(property "License" "Apache-2.0"
			(at 139.7 130.81 0)
			(effects
				(font
					(size 1.27 1.27)
					(thickness 0.15)
				)
				(justify left bottom)
				(hide yes)
			)
		)
		(property "Author" "Antmicro"
			(at 139.7 128.27 0)
			(effects
				(font
					(size 1.27 1.27)
					(thickness 0.15)
				)
				(justify left bottom)
				(hide yes)
			)
		)
		(property "Voltage" "50V"
			(at 139.7 125.73 0)
			(effects
				(font
					(size 1.27 1.27)
				)
				(justify left bottom)
				(hide yes)
			)
		)
		(property "Dielectric" "X5R"
			(at 139.7 123.19 0)
			(effects
				(font
					(size 1.27 1.27)
				)
				(justify left bottom)
				(hide yes)
			)
		)
		(property "Public" "False"
			(at 139.7 120.65 0)
			(effects
				(font
					(size 1.27 1.27)
				)
				(justify left bottom)
				(hide yes)
			)
		)
		(pin "1"
		)
		(pin "2"
		)
		(instances
			(project "jetson-agx-thor-baseboard"
				(path ""
					(reference "C58")
					(unit 1)
				)
			)
		)
	)
	(symbol
		(lib_id "antmicroCapacitors0402:C_100n_0402")
		(at 293.37 157.48 90)
		(unit 1)
		(exclude_from_sim no)
		(in_bom yes)
		(on_board yes)
		(dnp no)
		(fields_autoplaced yes)
		(property "Reference" "C177"
			(at 295.91 153.6636 90)
			(effects
				(font
					(size 1.27 1.27)
					(thickness 0.15)
				)
				(justify right)
			)
		)
		(property "Value" "C_100n_0402"
			(at 303.53 137.16 0)
			(effects
				(font
					(size 1.27 1.27)
					(thickness 0.15)
				)
				(justify left bottom)
				(hide yes)
			)
		)
		(property "Footprint" "antmicro-footprints:C_0402_1005Metric"
			(at 306.07 137.16 0)
			(effects
				(font
					(size 1.27 1.27)
					(thickness 0.15)
				)
				(justify left bottom)
				(hide yes)
			)
		)
		(property "Datasheet" "https://www.murata.com/products/productdetail?partno=GRM155R61H104KE14%23"
			(at 308.61 137.16 0)
			(effects
				(font
					(size 1.27 1.27)
					(thickness 0.15)
				)
				(justify left bottom)
				(hide yes)
			)
		)
		(property "Description" "SMD Multilayer Ceramic Capacitor, 0.1 µF, 50 V, 0402 [1005 Metric], ± 10%, X5R, GRM Series"
			(at 293.37 157.48 0)
			(effects
				(font
					(size 1.27 1.27)
				)
				(hide yes)
			)
		)
		(property "MPN" "GRM155R61H104KE14D"
			(at 311.15 137.16 0)
			(effects
				(font
					(size 1.27 1.27)
					(thickness 0.15)
				)
				(justify left bottom)
				(hide yes)
			)
		)
		(property "Manufacturer" "Murata"
			(at 313.69 137.16 0)
			(effects
				(font
					(size 1.27 1.27)
					(thickness 0.15)
				)
				(justify left bottom)
				(hide yes)
			)
		)
		(property "License" "Apache-2.0"
			(at 316.23 137.16 0)
			(effects
				(font
					(size 1.27 1.27)
					(thickness 0.15)
				)
				(justify left bottom)
				(hide yes)
			)
		)
		(property "Author" "Antmicro"
			(at 318.77 137.16 0)
			(effects
				(font
					(size 1.27 1.27)
					(thickness 0.15)
				)
				(justify left bottom)
				(hide yes)
			)
		)
		(property "Val" "100n"
			(at 295.91 156.2036 90)
			(effects
				(font
					(size 1.27 1.27)
					(thickness 0.15)
				)
				(justify right)
			)
		)
		(property "Voltage" "50V"
			(at 321.31 137.16 0)
			(effects
				(font
					(size 1.27 1.27)
				)
				(justify left bottom)
				(hide yes)
			)
		)
		(property "Dielectric" "X5R"
			(at 323.85 137.16 0)
			(effects
				(font
					(size 1.27 1.27)
				)
				(justify left bottom)
				(hide yes)
			)
		)
		(pin "2"
		)
		(pin "1"
		)
		(instances
			(project "jetson-agx-thor-baseboard"
				(path ""
					(reference "C177")
					(unit 1)
				)
			)
		)
	)
	(symbol
		(lib_id "antmicroCapacitors0402:C_100n_0402")
		(at 275.59 157.48 90)
		(unit 1)
		(exclude_from_sim no)
		(in_bom yes)
		(on_board yes)
		(dnp no)
		(fields_autoplaced yes)
		(property "Reference" "C175"
			(at 278.13 153.6636 90)
			(effects
				(font
					(size 1.27 1.27)
					(thickness 0.15)
				)
				(justify right)
			)
		)
		(property "Value" "C_100n_0402"
			(at 285.75 137.16 0)
			(effects
				(font
					(size 1.27 1.27)
					(thickness 0.15)
				)
				(justify left bottom)
				(hide yes)
			)
		)
		(property "Footprint" "antmicro-footprints:C_0402_1005Metric"
			(at 288.29 137.16 0)
			(effects
				(font
					(size 1.27 1.27)
					(thickness 0.15)
				)
				(justify left bottom)
				(hide yes)
			)
		)
		(property "Datasheet" "https://www.murata.com/products/productdetail?partno=GRM155R61H104KE14%23"
			(at 290.83 137.16 0)
			(effects
				(font
					(size 1.27 1.27)
					(thickness 0.15)
				)
				(justify left bottom)
				(hide yes)
			)
		)
		(property "Description" "SMD Multilayer Ceramic Capacitor, 0.1 µF, 50 V, 0402 [1005 Metric], ± 10%, X5R, GRM Series"
			(at 275.59 157.48 0)
			(effects
				(font
					(size 1.27 1.27)
				)
				(hide yes)
			)
		)
		(property "MPN" "GRM155R61H104KE14D"
			(at 293.37 137.16 0)
			(effects
				(font
					(size 1.27 1.27)
					(thickness 0.15)
				)
				(justify left bottom)
				(hide yes)
			)
		)
		(property "Manufacturer" "Murata"
			(at 295.91 137.16 0)
			(effects
				(font
					(size 1.27 1.27)
					(thickness 0.15)
				)
				(justify left bottom)
				(hide yes)
			)
		)
		(property "License" "Apache-2.0"
			(at 298.45 137.16 0)
			(effects
				(font
					(size 1.27 1.27)
					(thickness 0.15)
				)
				(justify left bottom)
				(hide yes)
			)
		)
		(property "Author" "Antmicro"
			(at 300.99 137.16 0)
			(effects
				(font
					(size 1.27 1.27)
					(thickness 0.15)
				)
				(justify left bottom)
				(hide yes)
			)
		)
		(property "Val" "100n"
			(at 278.13 156.2036 90)
			(effects
				(font
					(size 1.27 1.27)
					(thickness 0.15)
				)
				(justify right)
			)
		)
		(property "Voltage" "50V"
			(at 303.53 137.16 0)
			(effects
				(font
					(size 1.27 1.27)
				)
				(justify left bottom)
				(hide yes)
			)
		)
		(property "Dielectric" "X5R"
			(at 306.07 137.16 0)
			(effects
				(font
					(size 1.27 1.27)
				)
				(justify left bottom)
				(hide yes)
			)
		)
		(pin "2"
		)
		(pin "1"
		)
		(instances
			(project "jetson-agx-thor-baseboard"
				(path ""
					(reference "C175")
					(unit 1)
				)
			)
		)
	)
	(symbol
		(lib_id "antmicropower:GND")
		(at 156.21 100.33 0)
		(mirror y)
		(unit 1)
		(exclude_from_sim no)
		(in_bom yes)
		(on_board yes)
		(dnp no)
		(property "Reference" "#PWR0340"
			(at 147.32 102.87 0)
			(effects
				(font
					(size 1.27 1.27)
					(thickness 0.15)
				)
				(justify left bottom)
				(hide yes)
			)
		)
		(property "Value" "GND"
			(at 156.21 104.14 0)
			(effects
				(font
					(size 1.27 1.27)
					(thickness 0.15)
				)
			)
		)
		(property "Footprint" ""
			(at 147.32 107.95 0)
			(effects
				(font
					(size 1.27 1.27)
					(thickness 0.15)
				)
				(justify left bottom)
				(hide yes)
			)
		)
		(property "Datasheet" ""
			(at 147.32 113.03 0)
			(effects
				(font
					(size 1.27 1.27)
					(thickness 0.15)
				)
				(justify left bottom)
				(hide yes)
			)
		)
		(property "Description" ""
			(at 156.21 100.33 0)
			(effects
				(font
					(size 1.27 1.27)
				)
				(hide yes)
			)
		)
		(property "Author" "Antmicro"
			(at 147.32 107.95 0)
			(effects
				(font
					(size 1.27 1.27)
					(thickness 0.15)
				)
				(justify left bottom)
				(hide yes)
			)
		)
		(property "License" "Apache-2.0"
			(at 147.32 110.49 0)
			(effects
				(font
					(size 1.27 1.27)
					(thickness 0.15)
				)
				(justify left bottom)
				(hide yes)
			)
		)
		(pin "1"
		)
		(instances
			(project "jetson-agx-thor-baseboard"
				(path ""
					(reference "#PWR0340")
					(unit 1)
				)
			)
		)
	)
	(symbol
		(lib_id "antmicroCapacitors0402:C_100n_0402")
		(at 266.7 157.48 90)
		(unit 1)
		(exclude_from_sim no)
		(in_bom yes)
		(on_board yes)
		(dnp no)
		(fields_autoplaced yes)
		(property "Reference" "C174"
			(at 269.24 153.6636 90)
			(effects
				(font
					(size 1.27 1.27)
					(thickness 0.15)
				)
				(justify right)
			)
		)
		(property "Value" "C_100n_0402"
			(at 276.86 137.16 0)
			(effects
				(font
					(size 1.27 1.27)
					(thickness 0.15)
				)
				(justify left bottom)
				(hide yes)
			)
		)
		(property "Footprint" "antmicro-footprints:C_0402_1005Metric"
			(at 279.4 137.16 0)
			(effects
				(font
					(size 1.27 1.27)
					(thickness 0.15)
				)
				(justify left bottom)
				(hide yes)
			)
		)
		(property "Datasheet" "https://www.murata.com/products/productdetail?partno=GRM155R61H104KE14%23"
			(at 281.94 137.16 0)
			(effects
				(font
					(size 1.27 1.27)
					(thickness 0.15)
				)
				(justify left bottom)
				(hide yes)
			)
		)
		(property "Description" "SMD Multilayer Ceramic Capacitor, 0.1 µF, 50 V, 0402 [1005 Metric], ± 10%, X5R, GRM Series"
			(at 266.7 157.48 0)
			(effects
				(font
					(size 1.27 1.27)
				)
				(hide yes)
			)
		)
		(property "MPN" "GRM155R61H104KE14D"
			(at 284.48 137.16 0)
			(effects
				(font
					(size 1.27 1.27)
					(thickness 0.15)
				)
				(justify left bottom)
				(hide yes)
			)
		)
		(property "Manufacturer" "Murata"
			(at 287.02 137.16 0)
			(effects
				(font
					(size 1.27 1.27)
					(thickness 0.15)
				)
				(justify left bottom)
				(hide yes)
			)
		)
		(property "License" "Apache-2.0"
			(at 289.56 137.16 0)
			(effects
				(font
					(size 1.27 1.27)
					(thickness 0.15)
				)
				(justify left bottom)
				(hide yes)
			)
		)
		(property "Author" "Antmicro"
			(at 292.1 137.16 0)
			(effects
				(font
					(size 1.27 1.27)
					(thickness 0.15)
				)
				(justify left bottom)
				(hide yes)
			)
		)
		(property "Val" "100n"
			(at 269.24 156.2036 90)
			(effects
				(font
					(size 1.27 1.27)
					(thickness 0.15)
				)
				(justify right)
			)
		)
		(property "Voltage" "50V"
			(at 294.64 137.16 0)
			(effects
				(font
					(size 1.27 1.27)
				)
				(justify left bottom)
				(hide yes)
			)
		)
		(property "Dielectric" "X5R"
			(at 297.18 137.16 0)
			(effects
				(font
					(size 1.27 1.27)
				)
				(justify left bottom)
				(hide yes)
			)
		)
		(pin "2"
		)
		(pin "1"
		)
		(instances
			(project "jetson-agx-thor-baseboard"
				(path ""
					(reference "C174")
					(unit 1)
				)
			)
		)
	)
	(symbol
		(lib_id "antmicroCapacitors0402:C_100n_0402")
		(at 257.81 157.48 90)
		(unit 1)
		(exclude_from_sim no)
		(in_bom yes)
		(on_board yes)
		(dnp no)
		(fields_autoplaced yes)
		(property "Reference" "C173"
			(at 260.35 153.6636 90)
			(effects
				(font
					(size 1.27 1.27)
					(thickness 0.15)
				)
				(justify right)
			)
		)
		(property "Value" "C_100n_0402"
			(at 267.97 137.16 0)
			(effects
				(font
					(size 1.27 1.27)
					(thickness 0.15)
				)
				(justify left bottom)
				(hide yes)
			)
		)
		(property "Footprint" "antmicro-footprints:C_0402_1005Metric"
			(at 270.51 137.16 0)
			(effects
				(font
					(size 1.27 1.27)
					(thickness 0.15)
				)
				(justify left bottom)
				(hide yes)
			)
		)
		(property "Datasheet" "https://www.murata.com/products/productdetail?partno=GRM155R61H104KE14%23"
			(at 273.05 137.16 0)
			(effects
				(font
					(size 1.27 1.27)
					(thickness 0.15)
				)
				(justify left bottom)
				(hide yes)
			)
		)
		(property "Description" "SMD Multilayer Ceramic Capacitor, 0.1 µF, 50 V, 0402 [1005 Metric], ± 10%, X5R, GRM Series"
			(at 257.81 157.48 0)
			(effects
				(font
					(size 1.27 1.27)
				)
				(hide yes)
			)
		)
		(property "MPN" "GRM155R61H104KE14D"
			(at 275.59 137.16 0)
			(effects
				(font
					(size 1.27 1.27)
					(thickness 0.15)
				)
				(justify left bottom)
				(hide yes)
			)
		)
		(property "Manufacturer" "Murata"
			(at 278.13 137.16 0)
			(effects
				(font
					(size 1.27 1.27)
					(thickness 0.15)
				)
				(justify left bottom)
				(hide yes)
			)
		)
		(property "License" "Apache-2.0"
			(at 280.67 137.16 0)
			(effects
				(font
					(size 1.27 1.27)
					(thickness 0.15)
				)
				(justify left bottom)
				(hide yes)
			)
		)
		(property "Author" "Antmicro"
			(at 283.21 137.16 0)
			(effects
				(font
					(size 1.27 1.27)
					(thickness 0.15)
				)
				(justify left bottom)
				(hide yes)
			)
		)
		(property "Val" "100n"
			(at 260.35 156.2036 90)
			(effects
				(font
					(size 1.27 1.27)
					(thickness 0.15)
				)
				(justify right)
			)
		)
		(property "Voltage" "50V"
			(at 285.75 137.16 0)
			(effects
				(font
					(size 1.27 1.27)
				)
				(justify left bottom)
				(hide yes)
			)
		)
		(property "Dielectric" "X5R"
			(at 288.29 137.16 0)
			(effects
				(font
					(size 1.27 1.27)
				)
				(justify left bottom)
				(hide yes)
			)
		)
		(pin "2"
		)
		(pin "1"
		)
		(instances
			(project "jetson-agx-thor-baseboard"
				(path ""
					(reference "C173")
					(unit 1)
				)
			)
		)
	)
	(symbol
		(lib_id "antmicropower:GND")
		(at 284.48 162.56 0)
		(mirror y)
		(unit 1)
		(exclude_from_sim no)
		(in_bom yes)
		(on_board yes)
		(dnp no)
		(property "Reference" "#PWR0357"
			(at 275.59 165.1 0)
			(effects
				(font
					(size 1.27 1.27)
					(thickness 0.15)
				)
				(justify left bottom)
				(hide yes)
			)
		)
		(property "Value" "GND"
			(at 284.48 166.37 0)
			(effects
				(font
					(size 1.27 1.27)
					(thickness 0.15)
				)
			)
		)
		(property "Footprint" ""
			(at 275.59 170.18 0)
			(effects
				(font
					(size 1.27 1.27)
					(thickness 0.15)
				)
				(justify left bottom)
				(hide yes)
			)
		)
		(property "Datasheet" ""
			(at 275.59 175.26 0)
			(effects
				(font
					(size 1.27 1.27)
					(thickness 0.15)
				)
				(justify left bottom)
				(hide yes)
			)
		)
		(property "Description" ""
			(at 284.48 162.56 0)
			(effects
				(font
					(size 1.27 1.27)
				)
				(hide yes)
			)
		)
		(property "Author" "Antmicro"
			(at 275.59 170.18 0)
			(effects
				(font
					(size 1.27 1.27)
					(thickness 0.15)
				)
				(justify left bottom)
				(hide yes)
			)
		)
		(property "License" "Apache-2.0"
			(at 275.59 172.72 0)
			(effects
				(font
					(size 1.27 1.27)
					(thickness 0.15)
				)
				(justify left bottom)
				(hide yes)
			)
		)
		(pin "1"
		)
		(instances
			(project "jetson-agx-thor-baseboard"
				(path ""
					(reference "#PWR0357")
					(unit 1)
				)
			)
		)
	)
	(symbol
		(lib_id "antmicroCapacitors0402:C_100n_0402")
		(at 165.1 99.06 90)
		(unit 1)
		(exclude_from_sim no)
		(in_bom yes)
		(on_board yes)
		(dnp no)
		(fields_autoplaced yes)
		(property "Reference" "C180"
			(at 167.64 95.2436 90)
			(effects
				(font
					(size 1.27 1.27)
					(thickness 0.15)
				)
				(justify right)
			)
		)
		(property "Value" "C_100n_0402"
			(at 175.26 78.74 0)
			(effects
				(font
					(size 1.27 1.27)
					(thickness 0.15)
				)
				(justify left bottom)
				(hide yes)
			)
		)
		(property "Footprint" "antmicro-footprints:C_0402_1005Metric"
			(at 177.8 78.74 0)
			(effects
				(font
					(size 1.27 1.27)
					(thickness 0.15)
				)
				(justify left bottom)
				(hide yes)
			)
		)
		(property "Datasheet" "https://www.murata.com/products/productdetail?partno=GRM155R61H104KE14%23"
			(at 180.34 78.74 0)
			(effects
				(font
					(size 1.27 1.27)
					(thickness 0.15)
				)
				(justify left bottom)
				(hide yes)
			)
		)
		(property "Description" "SMD Multilayer Ceramic Capacitor, 0.1 µF, 50 V, 0402 [1005 Metric], ± 10%, X5R, GRM Series"
			(at 165.1 99.06 0)
			(effects
				(font
					(size 1.27 1.27)
				)
				(hide yes)
			)
		)
		(property "MPN" "GRM155R61H104KE14D"
			(at 182.88 78.74 0)
			(effects
				(font
					(size 1.27 1.27)
					(thickness 0.15)
				)
				(justify left bottom)
				(hide yes)
			)
		)
		(property "Manufacturer" "Murata"
			(at 185.42 78.74 0)
			(effects
				(font
					(size 1.27 1.27)
					(thickness 0.15)
				)
				(justify left bottom)
				(hide yes)
			)
		)
		(property "License" "Apache-2.0"
			(at 187.96 78.74 0)
			(effects
				(font
					(size 1.27 1.27)
					(thickness 0.15)
				)
				(justify left bottom)
				(hide yes)
			)
		)
		(property "Author" "Antmicro"
			(at 190.5 78.74 0)
			(effects
				(font
					(size 1.27 1.27)
					(thickness 0.15)
				)
				(justify left bottom)
				(hide yes)
			)
		)
		(property "Val" "100n"
			(at 167.64 97.7836 90)
			(effects
				(font
					(size 1.27 1.27)
					(thickness 0.15)
				)
				(justify right)
			)
		)
		(property "Voltage" "50V"
			(at 193.04 78.74 0)
			(effects
				(font
					(size 1.27 1.27)
				)
				(justify left bottom)
				(hide yes)
			)
		)
		(property "Dielectric" "X5R"
			(at 195.58 78.74 0)
			(effects
				(font
					(size 1.27 1.27)
				)
				(justify left bottom)
				(hide yes)
			)
		)
		(pin "2"
		)
		(pin "1"
		)
		(instances
			(project "jetson-agx-thor-baseboard"
				(path ""
					(reference "C180")
					(unit 1)
				)
			)
		)
	)
	(symbol
		(lib_id "antmicropower:+1V8")
		(at 147.32 113.03 0)
		(unit 1)
		(exclude_from_sim no)
		(in_bom yes)
		(on_board yes)
		(dnp no)
		(property "Reference" "#PWR0649"
			(at 147.32 116.84 0)
			(effects
				(font
					(size 1.27 1.27)
				)
				(justify left bottom)
				(hide yes)
			)
		)
		(property "Value" "+1V8"
			(at 144.145 109.855 0)
			(effects
				(font
					(size 1.27 1.27)
					(thickness 0.15)
				)
				(justify left bottom)
			)
		)
		(property "Footprint" ""
			(at 162.56 120.65 0)
			(effects
				(font
					(size 1.27 1.27)
					(thickness 0.15)
				)
				(justify left bottom)
				(hide yes)
			)
		)
		(property "Datasheet" ""
			(at 162.56 123.19 0)
			(effects
				(font
					(size 1.27 1.27)
					(thickness 0.15)
				)
				(justify left bottom)
				(hide yes)
			)
		)
		(property "Description" ""
			(at 147.32 113.03 0)
			(effects
				(font
					(size 1.27 1.27)
				)
				(hide yes)
			)
		)
		(property "Author" "Antmicro"
			(at 162.56 118.11 0)
			(effects
				(font
					(size 1.27 1.27)
					(thickness 0.15)
				)
				(justify left bottom)
				(hide yes)
			)
		)
		(property "License" "Apache-2.0"
			(at 162.56 120.65 0)
			(effects
				(font
					(size 1.27 1.27)
					(thickness 0.15)
				)
				(justify left bottom)
				(hide yes)
			)
		)
		(pin "1"
		)
		(instances
			(project "jetson-agx-thor-baseboard"
				(path ""
					(reference "#PWR0649")
					(unit 1)
				)
			)
		)
	)
	(symbol
		(lib_id "antmicroResistors0402:R_0R_0402")
		(at 138.43 125.73 0)
		(unit 1)
		(exclude_from_sim no)
		(in_bom yes)
		(on_board yes)
		(dnp no)
		(property "Reference" "R185"
			(at 136.144 124.46 0)
			(effects
				(font
					(size 1.27 1.27)
					(thickness 0.15)
				)
			)
		)
		(property "Value" "R_0R_0402"
			(at 158.75 138.43 0)
			(effects
				(font
					(size 1.27 1.27)
					(thickness 0.15)
				)
				(justify left bottom)
				(hide yes)
			)
		)
		(property "Footprint" "antmicro-footprints:R_0402_1005Metric"
			(at 158.75 140.97 0)
			(effects
				(font
					(size 1.27 1.27)
					(thickness 0.15)
				)
				(justify left bottom)
				(hide yes)
			)
		)
		(property "Datasheet" "https://industrial.panasonic.com/cdbs/www-data/pdf/RDA0000/AOA0000C301.pdf"
			(at 158.75 143.51 0)
			(effects
				(font
					(size 1.27 1.27)
					(thickness 0.15)
				)
				(justify left bottom)
				(hide yes)
			)
		)
		(property "Description" "SMD Chip Resistor, Jumper, 0 ohm, 100 mW, 0402 [1005 Metric], Thick Film, General Purpose"
			(at 138.43 125.73 0)
			(effects
				(font
					(size 1.27 1.27)
				)
				(hide yes)
			)
		)
		(property "MPN" "ERJ2GE0R00X"
			(at 158.75 146.05 0)
			(effects
				(font
					(size 1.27 1.27)
					(thickness 0.15)
				)
				(justify left bottom)
				(hide yes)
			)
		)
		(property "Manufacturer" "Panasonic"
			(at 158.75 148.59 0)
			(effects
				(font
					(size 1.27 1.27)
					(thickness 0.15)
				)
				(justify left bottom)
				(hide yes)
			)
		)
		(property "License" "Apache-2.0"
			(at 158.75 151.13 0)
			(effects
				(font
					(size 1.27 1.27)
					(thickness 0.15)
				)
				(justify left bottom)
				(hide yes)
			)
		)
		(property "Author" "Antmicro"
			(at 158.75 153.67 0)
			(effects
				(font
					(size 1.27 1.27)
					(thickness 0.15)
				)
				(justify left bottom)
				(hide yes)
			)
		)
		(property "Val" "0R"
			(at 144.526 124.46 0)
			(effects
				(font
					(size 1.27 1.27)
					(thickness 0.15)
				)
			)
		)
		(property "Tolerance" "~"
			(at 158.75 135.89 0)
			(effects
				(font
					(size 1.27 1.27)
				)
				(justify left bottom)
				(hide yes)
			)
		)
		(property "Current" "1A"
			(at 158.75 156.21 0)
			(effects
				(font
					(size 1.27 1.27)
					(thickness 0.15)
				)
				(justify left bottom)
				(hide yes)
			)
		)
		(pin "1"
		)
		(pin "2"
		)
		(instances
			(project "jetson-agx-thor-baseboard"
				(path ""
					(reference "R185")
					(unit 1)
				)
			)
		)
	)
	(symbol
		(lib_id "antmicropower:GND")
		(at 248.92 162.56 0)
		(mirror y)
		(unit 1)
		(exclude_from_sim no)
		(in_bom yes)
		(on_board yes)
		(dnp no)
		(property "Reference" "#PWR0351"
			(at 240.03 165.1 0)
			(effects
				(font
					(size 1.27 1.27)
					(thickness 0.15)
				)
				(justify left bottom)
				(hide yes)
			)
		)
		(property "Value" "GND"
			(at 248.92 166.37 0)
			(effects
				(font
					(size 1.27 1.27)
					(thickness 0.15)
				)
			)
		)
		(property "Footprint" ""
			(at 240.03 170.18 0)
			(effects
				(font
					(size 1.27 1.27)
					(thickness 0.15)
				)
				(justify left bottom)
				(hide yes)
			)
		)
		(property "Datasheet" ""
			(at 240.03 175.26 0)
			(effects
				(font
					(size 1.27 1.27)
					(thickness 0.15)
				)
				(justify left bottom)
				(hide yes)
			)
		)
		(property "Description" ""
			(at 248.92 162.56 0)
			(effects
				(font
					(size 1.27 1.27)
				)
				(hide yes)
			)
		)
		(property "Author" "Antmicro"
			(at 240.03 170.18 0)
			(effects
				(font
					(size 1.27 1.27)
					(thickness 0.15)
				)
				(justify left bottom)
				(hide yes)
			)
		)
		(property "License" "Apache-2.0"
			(at 240.03 172.72 0)
			(effects
				(font
					(size 1.27 1.27)
					(thickness 0.15)
				)
				(justify left bottom)
				(hide yes)
			)
		)
		(pin "1"
		)
		(instances
			(project "jetson-agx-thor-baseboard"
				(path ""
					(reference "#PWR0351")
					(unit 1)
				)
			)
		)
	)
	(symbol
		(lib_id "antmicropower:GND")
		(at 266.7 162.56 0)
		(mirror y)
		(unit 1)
		(exclude_from_sim no)
		(in_bom yes)
		(on_board yes)
		(dnp no)
		(property "Reference" "#PWR0354"
			(at 257.81 165.1 0)
			(effects
				(font
					(size 1.27 1.27)
					(thickness 0.15)
				)
				(justify left bottom)
				(hide yes)
			)
		)
		(property "Value" "GND"
			(at 266.7 166.37 0)
			(effects
				(font
					(size 1.27 1.27)
					(thickness 0.15)
				)
			)
		)
		(property "Footprint" ""
			(at 257.81 170.18 0)
			(effects
				(font
					(size 1.27 1.27)
					(thickness 0.15)
				)
				(justify left bottom)
				(hide yes)
			)
		)
		(property "Datasheet" ""
			(at 257.81 175.26 0)
			(effects
				(font
					(size 1.27 1.27)
					(thickness 0.15)
				)
				(justify left bottom)
				(hide yes)
			)
		)
		(property "Description" ""
			(at 266.7 162.56 0)
			(effects
				(font
					(size 1.27 1.27)
				)
				(hide yes)
			)
		)
		(property "Author" "Antmicro"
			(at 257.81 170.18 0)
			(effects
				(font
					(size 1.27 1.27)
					(thickness 0.15)
				)
				(justify left bottom)
				(hide yes)
			)
		)
		(property "License" "Apache-2.0"
			(at 257.81 172.72 0)
			(effects
				(font
					(size 1.27 1.27)
					(thickness 0.15)
				)
				(justify left bottom)
				(hide yes)
			)
		)
		(pin "1"
		)
		(instances
			(project "jetson-agx-thor-baseboard"
				(path ""
					(reference "#PWR0354")
					(unit 1)
				)
			)
		)
	)
	(symbol
		(lib_id "antmicroResistors0402:R_0R_0402")
		(at 175.26 140.97 0)
		(unit 1)
		(exclude_from_sim no)
		(in_bom yes)
		(on_board yes)
		(dnp no)
		(property "Reference" "R198"
			(at 172.974 139.7 0)
			(effects
				(font
					(size 1.27 1.27)
					(thickness 0.15)
				)
			)
		)
		(property "Value" "R_0R_0402"
			(at 195.58 153.67 0)
			(effects
				(font
					(size 1.27 1.27)
					(thickness 0.15)
				)
				(justify left bottom)
				(hide yes)
			)
		)
		(property "Footprint" "antmicro-footprints:R_0402_1005Metric"
			(at 195.58 156.21 0)
			(effects
				(font
					(size 1.27 1.27)
					(thickness 0.15)
				)
				(justify left bottom)
				(hide yes)
			)
		)
		(property "Datasheet" "https://industrial.panasonic.com/cdbs/www-data/pdf/RDA0000/AOA0000C301.pdf"
			(at 195.58 158.75 0)
			(effects
				(font
					(size 1.27 1.27)
					(thickness 0.15)
				)
				(justify left bottom)
				(hide yes)
			)
		)
		(property "Description" "SMD Chip Resistor, Jumper, 0 ohm, 100 mW, 0402 [1005 Metric], Thick Film, General Purpose"
			(at 175.26 140.97 0)
			(effects
				(font
					(size 1.27 1.27)
				)
				(hide yes)
			)
		)
		(property "MPN" "ERJ2GE0R00X"
			(at 195.58 161.29 0)
			(effects
				(font
					(size 1.27 1.27)
					(thickness 0.15)
				)
				(justify left bottom)
				(hide yes)
			)
		)
		(property "Manufacturer" "Panasonic"
			(at 195.58 163.83 0)
			(effects
				(font
					(size 1.27 1.27)
					(thickness 0.15)
				)
				(justify left bottom)
				(hide yes)
			)
		)
		(property "License" "Apache-2.0"
			(at 195.58 166.37 0)
			(effects
				(font
					(size 1.27 1.27)
					(thickness 0.15)
				)
				(justify left bottom)
				(hide yes)
			)
		)
		(property "Author" "Antmicro"
			(at 195.58 168.91 0)
			(effects
				(font
					(size 1.27 1.27)
					(thickness 0.15)
				)
				(justify left bottom)
				(hide yes)
			)
		)
		(property "Val" "0R"
			(at 181.356 139.7 0)
			(effects
				(font
					(size 1.27 1.27)
					(thickness 0.15)
				)
			)
		)
		(property "Tolerance" "~"
			(at 195.58 151.13 0)
			(effects
				(font
					(size 1.27 1.27)
				)
				(justify left bottom)
				(hide yes)
			)
		)
		(property "Current" "1A"
			(at 195.58 171.45 0)
			(effects
				(font
					(size 1.27 1.27)
					(thickness 0.15)
				)
				(justify left bottom)
				(hide yes)
			)
		)
		(pin "1"
		)
		(pin "2"
		)
		(instances
			(project "jetson-agx-thor-baseboard"
				(path ""
					(reference "R198")
					(unit 1)
				)
			)
		)
	)
	(symbol
		(lib_id "antmicroCapacitors0402:C_100n_0402")
		(at 240.03 157.48 90)
		(unit 1)
		(exclude_from_sim no)
		(in_bom yes)
		(on_board yes)
		(dnp no)
		(fields_autoplaced yes)
		(property "Reference" "C169"
			(at 242.57 153.6636 90)
			(effects
				(font
					(size 1.27 1.27)
					(thickness 0.15)
				)
				(justify right)
			)
		)
		(property "Value" "C_100n_0402"
			(at 250.19 137.16 0)
			(effects
				(font
					(size 1.27 1.27)
					(thickness 0.15)
				)
				(justify left bottom)
				(hide yes)
			)
		)
		(property "Footprint" "antmicro-footprints:C_0402_1005Metric"
			(at 252.73 137.16 0)
			(effects
				(font
					(size 1.27 1.27)
					(thickness 0.15)
				)
				(justify left bottom)
				(hide yes)
			)
		)
		(property "Datasheet" "https://www.murata.com/products/productdetail?partno=GRM155R61H104KE14%23"
			(at 255.27 137.16 0)
			(effects
				(font
					(size 1.27 1.27)
					(thickness 0.15)
				)
				(justify left bottom)
				(hide yes)
			)
		)
		(property "Description" "SMD Multilayer Ceramic Capacitor, 0.1 µF, 50 V, 0402 [1005 Metric], ± 10%, X5R, GRM Series"
			(at 240.03 157.48 0)
			(effects
				(font
					(size 1.27 1.27)
				)
				(hide yes)
			)
		)
		(property "MPN" "GRM155R61H104KE14D"
			(at 257.81 137.16 0)
			(effects
				(font
					(size 1.27 1.27)
					(thickness 0.15)
				)
				(justify left bottom)
				(hide yes)
			)
		)
		(property "Manufacturer" "Murata"
			(at 260.35 137.16 0)
			(effects
				(font
					(size 1.27 1.27)
					(thickness 0.15)
				)
				(justify left bottom)
				(hide yes)
			)
		)
		(property "License" "Apache-2.0"
			(at 262.89 137.16 0)
			(effects
				(font
					(size 1.27 1.27)
					(thickness 0.15)
				)
				(justify left bottom)
				(hide yes)
			)
		)
		(property "Author" "Antmicro"
			(at 265.43 137.16 0)
			(effects
				(font
					(size 1.27 1.27)
					(thickness 0.15)
				)
				(justify left bottom)
				(hide yes)
			)
		)
		(property "Val" "100n"
			(at 242.57 156.2036 90)
			(effects
				(font
					(size 1.27 1.27)
					(thickness 0.15)
				)
				(justify right)
			)
		)
		(property "Voltage" "50V"
			(at 267.97 137.16 0)
			(effects
				(font
					(size 1.27 1.27)
				)
				(justify left bottom)
				(hide yes)
			)
		)
		(property "Dielectric" "X5R"
			(at 270.51 137.16 0)
			(effects
				(font
					(size 1.27 1.27)
				)
				(justify left bottom)
				(hide yes)
			)
		)
		(pin "2"
		)
		(pin "1"
		)
		(instances
			(project "jetson-agx-thor-baseboard"
				(path ""
					(reference "C169")
					(unit 1)
				)
			)
		)
	)
)
